FILE_TYPE = MACRO_DRAWING;
SET COLOR_WIRE YELLOW;
SET COLOR_PROP ORANGE;
SET COLOR_DOT WHITE;
SET COLOR_ARC YELLOW;
SET COLOR_BODY GREEN;
SET COLOR_NOTE PURPLE;
SET PROP_DISPLAY VALUE;
SET PAGE_NUMBER P8;
FORCEADD OFFPAGE_IN..1
(-11050 8750);
FORCEPROP 2 LAST $XR0 19G9> 
J 0
(-11233 8750);
DISPLAY 0.638298 (-11233 8750);
PAINT MONO (-11233 8750);
FORCEPROP 2 LAST PATH I1
J 0
(-11200 8800);
DISPLAY 1.021277 (-11200 8800);
DISPLAY INVISIBLE (-11200 8800);
FORCEPROP 1 LAST OFFPAGE TRUE
J 0
(-11040 8805);
DISPLAY 0.808511 (-11040 8805);
PAINT GREEN (-11040 8805);
DISPLAY INVISIBLE (-11040 8805);
FORCEPROP 1 LAST BODY_TYPE COMMENT
J 0
(-11040 8885);
DISPLAY 0.808511 (-11040 8885);
PAINT GREEN (-11040 8885);
DISPLAY INVISIBLE (-11040 8885);
FORCEPROP 1 LAST CDS_LMAN_SYM_OUTLINE -50,50,50,-50
J 0
(-11050 8750);
DISPLAY 0.468085 (-11050 8750);
PAINT GREEN (-11050 8750);
DISPLAY INVISIBLE (-11050 8750);
FORCEPROP 2 LAST CDS_LIB cls
J 0
(-11050 8750);
DISPLAY INVISIBLE (-11050 8750);
FORCEADD VCC..1
(-2700 9100);
FORCEPROP 3 LASTPIN (-2650 9050) SIG_NAME XP1R8V_FPGA\g
J 0
(-2640 9060);
DISPLAY 0.659574 (-2640 9060);
PAINT MONO (-2640 9060);
DISPLAY INVISIBLE (-2640 9060);
FORCEPROP 1 LAST PATH I13
J 0
(-2665 9190);
DISPLAY 0.808511 (-2665 9190);
PAINT GREEN (-2665 9190);
DISPLAY INVISIBLE (-2665 9190);
FORCEPROP 1 LAST BODY_TYPE PLUMBING
J 0
(-2745 9057);
DISPLAY 0.340426 (-2745 9057);
PAINT GREEN (-2745 9057);
DISPLAY INVISIBLE (-2745 9057);
FORCEPROP 2 LAST CDS_LIB cls
J 0
(-2700 9100);
DISPLAY INVISIBLE (-2700 9100);
FORCEPROP 1 LAST CDS_LMAN_SYM_OUTLINE -250,250,250,-250
J 0
(-2700 9100);
DISPLAY 0.468085 (-2700 9100);
PAINT GREEN (-2700 9100);
DISPLAY INVISIBLE (-2700 9100);
FORCEPROP 0 LAST VOLTAGE 1.8V
J 0
(-2900 9250);
DISPLAY 1.021277 (-2900 9250);
DISPLAY BOTH (-2900 9250);
FORCEPROP 1 LAST HDL_POWER XP1R8V_FPGA
J 1
(-2645 9155);
DISPLAY 1.021277 (-2645 9155);
PAINT GREEN (-2645 9155);
FORCEADD CAPACITOR..2
R 2
(-2950 8500);
FORCEPROP 1 LAST $LOCATION C276
J 2
(-2650 8450);
DISPLAY 1.212766 (-2650 8450);
PAINT GREEN (-2650 8450);
FORCEPROP 0 LAST CDS_LOCATION C276
J 0
(-2550 8650);
DISPLAY 1.021277 (-2550 8650);
DISPLAY INVISIBLE (-2550 8650);
FORCEPROP 0 LAST $SEC 1
J 0
(-2550 8650);
DISPLAY 0.680851 (-2550 8650);
PAINT MONO (-2550 8650);
DISPLAY INVISIBLE (-2550 8650);
FORCEPROP 0 LAST CDS_SEC 1
J 0
(-2550 8650);
DISPLAY 1.021277 (-2550 8650);
DISPLAY INVISIBLE (-2550 8650);
FORCEPROP 0 LASTPIN (-2950 8600) $PN 1
R 1
J 0
(-2960 8610);
DISPLAY 0.680851 (-2960 8610);
PAINT MONO (-2960 8610);
FORCEPROP 0 LASTPIN (-2950 8350) $PN 2
R 1
J 2
(-2960 8340);
DISPLAY 0.680851 (-2960 8340);
PAINT MONO (-2960 8340);
FORCEPROP 1 LAST PATH I16
J 2
(-2850 8550);
DISPLAY 1.212766 (-2850 8550);
PAINT GREEN (-2850 8550);
DISPLAY INVISIBLE (-2850 8550);
FORCEPROP 1 LAST CDS_LMAN_SYM_OUTLINE -50,0,50,-50
J 2
(-2950 8500);
DISPLAY 0.468085 (-2950 8500);
PAINT GREEN (-2950 8500);
DISPLAY INVISIBLE (-2950 8500);
FORCEPROP 2 LAST CDS_LIB passive
J 0
(-2950 8500);
DISPLAY INVISIBLE (-2950 8500);
FORCEPROP 1 LAST CLS_PN G105-0B104-EK
J 2
(-2850 8550);
DISPLAY 1.212766 (-2850 8550);
PAINT GREEN (-2850 8550);
DISPLAY INVISIBLE (-2850 8550);
FORCEPROP 1 LAST TOLERANCE 10%
J 2
(-2800 8600);
DISPLAY 1.212766 (-2800 8600);
PAINT GREEN (-2800 8600);
DISPLAY INVISIBLE (-2800 8600);
FORCEPROP 1 LAST VALUE 0.1UF
J 2
(-2550 8550);
DISPLAY 1.212766 (-2550 8550);
PAINT GREEN (-2550 8550);
FORCEPROP 0 LAST VOLTAGE 25V
J 0
(-2850 8350);
DISPLAY 1.021277 (-2850 8350);
FORCEPROP 0 LAST PACKAGE 0402
J 0
(-2850 8650);
DISPLAY 1.021277 (-2850 8650);
FORCEADD FERRITEBEAD..1
R 2
(-3300 8900);
FORCEPROP 1 LAST $LOCATION L18
J 0
(-3750 8900);
DISPLAY 1.212766 (-3750 8900);
PAINT GREEN (-3750 8900);
FORCEPROP 0 LAST CDS_LOCATION L18
J 0
(-2900 9000);
DISPLAY 1.021277 (-2900 9000);
DISPLAY INVISIBLE (-2900 9000);
FORCEPROP 0 LAST $SEC 1
J 0
(-2900 9000);
DISPLAY 0.680851 (-2900 9000);
PAINT MONO (-2900 9000);
DISPLAY INVISIBLE (-2900 9000);
FORCEPROP 0 LAST CDS_SEC 1
J 0
(-2900 9000);
DISPLAY 1.021277 (-2900 9000);
DISPLAY INVISIBLE (-2900 9000);
FORCEPROP 0 LASTPIN (-3200 8850) $PN 1
J 0
(-3190 8860);
DISPLAY 0.680851 (-3190 8860);
PAINT MONO (-3190 8860);
FORCEPROP 0 LASTPIN (-3600 8850) $PN 2
J 2
(-3610 8860);
DISPLAY 0.680851 (-3610 8860);
PAINT MONO (-3610 8860);
FORCEPROP 1 LAST CDS_LMAN_SYM_OUTLINE 0,0,200,-100
J 2
(-3300 8900);
DISPLAY 0.468085 (-3300 8900);
PAINT GREEN (-3300 8900);
DISPLAY INVISIBLE (-3300 8900);
FORCEPROP 2 LAST CDS_LIB passive
J 0
(-3300 8900);
DISPLAY INVISIBLE (-3300 8900);
FORCEPROP 1 LAST CLS_PN G191-10097-01
J 0
(-3250 8950);
DISPLAY 1.212766 (-3250 8950);
PAINT GREEN (-3250 8950);
DISPLAY INVISIBLE (-3250 8950);
FORCEPROP 1 LAST PATH I18
J 0
(-3250 8950);
DISPLAY 1.212766 (-3250 8950);
PAINT GREEN (-3250 8950);
DISPLAY INVISIBLE (-3250 8950);
FORCEPROP 1 LAST TOLERANCE 25%
J 2
(-3200 8950);
DISPLAY 1.212766 (-3200 8950);
PAINT GREEN (-3200 8950);
DISPLAY INVISIBLE (-3200 8950);
FORCEPROP 2 LAST DCR 1300MA 0.15OHM
J 2
(-3050 8750);
FORCEPROP 0 LAST PACKAGE 0603
J 0
(-3500 8950);
DISPLAY 1.021277 (-3500 8950);
FORCEPROP 1 LAST VALUE 600OHM
J 2
(-2900 8900);
DISPLAY 1.212766 (-2900 8900);
PAINT GREEN (-2900 8900);
FORCEADD CAPACITOR..2
R 2
(-3950 8500);
FORCEPROP 1 LAST $LOCATION C278
J 2
(-3650 8400);
DISPLAY 1.212766 (-3650 8400);
PAINT GREEN (-3650 8400);
FORCEPROP 0 LAST CDS_LOCATION C278
J 0
(-3550 8650);
DISPLAY 1.021277 (-3550 8650);
DISPLAY INVISIBLE (-3550 8650);
FORCEPROP 0 LAST $SEC 1
J 0
(-3550 8650);
DISPLAY 0.680851 (-3550 8650);
PAINT MONO (-3550 8650);
DISPLAY INVISIBLE (-3550 8650);
FORCEPROP 0 LAST CDS_SEC 1
J 0
(-3550 8650);
DISPLAY 1.021277 (-3550 8650);
DISPLAY INVISIBLE (-3550 8650);
FORCEPROP 0 LASTPIN (-3950 8600) $PN 1
R 1
J 0
(-3960 8610);
DISPLAY 0.680851 (-3960 8610);
PAINT MONO (-3960 8610);
FORCEPROP 0 LASTPIN (-3950 8350) $PN 2
R 1
J 2
(-3960 8340);
DISPLAY 0.680851 (-3960 8340);
PAINT MONO (-3960 8340);
FORCEPROP 1 LAST PATH I19
J 2
(-3850 8550);
DISPLAY 1.212766 (-3850 8550);
PAINT GREEN (-3850 8550);
DISPLAY INVISIBLE (-3850 8550);
FORCEPROP 1 LAST TOLERANCE 10%
J 2
(-3800 8600);
DISPLAY 1.212766 (-3800 8600);
PAINT GREEN (-3800 8600);
DISPLAY INVISIBLE (-3800 8600);
FORCEPROP 2 LAST CDS_LIB passive
J 0
(-3950 8500);
DISPLAY INVISIBLE (-3950 8500);
FORCEPROP 1 LAST CDS_LMAN_SYM_OUTLINE -50,0,50,-50
J 2
(-3950 8500);
DISPLAY 0.468085 (-3950 8500);
PAINT GREEN (-3950 8500);
DISPLAY INVISIBLE (-3950 8500);
FORCEPROP 1 LAST CLS_PN G105-0B104-EK
J 2
(-3850 8550);
DISPLAY 1.212766 (-3850 8550);
PAINT GREEN (-3850 8550);
DISPLAY INVISIBLE (-3850 8550);
FORCEPROP 0 LAST PACKAGE 0402
J 0
(-3850 8650);
DISPLAY 1.021277 (-3850 8650);
FORCEPROP 0 LAST VOLTAGE 25V
J 0
(-3800 8300);
DISPLAY 1.021277 (-3800 8300);
FORCEPROP 1 LAST VALUE 0.1UF
J 2
(-3550 8550);
DISPLAY 1.212766 (-3550 8550);
PAINT GREEN (-3550 8550);
FORCEADD OFFPAGE_BI..1
R 2
(-11050 8850);
FORCEPROP 2 LAST $XR0 19G9<> 
J 0
(-11269 8850);
DISPLAY 0.638298 (-11269 8850);
PAINT MONO (-11269 8850);
FORCEPROP 2 LAST PATH I2
J 0
(-11250 8900);
DISPLAY 1.021277 (-11250 8900);
DISPLAY INVISIBLE (-11250 8900);
FORCEPROP 1 LAST OFFPAGE TRUE
J 2
(-11060 8905);
DISPLAY 0.808511 (-11060 8905);
PAINT GREEN (-11060 8905);
DISPLAY INVISIBLE (-11060 8905);
FORCEPROP 1 LAST BODY_TYPE COMMENT
J 2
(-11060 8985);
DISPLAY 0.808511 (-11060 8985);
PAINT GREEN (-11060 8985);
DISPLAY INVISIBLE (-11060 8985);
FORCEPROP 1 LAST CDS_LMAN_SYM_OUTLINE -50,50,50,-50
J 2
(-11050 8850);
DISPLAY 0.468085 (-11050 8850);
PAINT GREEN (-11050 8850);
DISPLAY INVISIBLE (-11050 8850);
FORCEPROP 2 LAST CDS_LIB cls
J 0
(-11050 8850);
DISPLAY INVISIBLE (-11050 8850);
FORCEADD GND_SG..1
R 2
(-4800 7900);
FORCEPROP 3 LASTPIN (-4850 7950) SIG_NAME SG\g
J 0
(-4840 7960);
DISPLAY 0.659574 (-4840 7960);
PAINT MONO (-4840 7960);
DISPLAY INVISIBLE (-4840 7960);
FORCEPROP 1 LAST PATH I20
J 2
(-4835 7900);
DISPLAY 0.808511 (-4835 7900);
PAINT GREEN (-4835 7900);
DISPLAY INVISIBLE (-4835 7900);
FORCEPROP 1 LAST BODY_TYPE PLUMBING
J 2
(-4815 7885);
DISPLAY 0.808511 (-4815 7885);
PAINT GREEN (-4815 7885);
DISPLAY INVISIBLE (-4815 7885);
FORCEPROP 1 LAST CDS_LMAN_SYM_OUTLINE 0,0,100,-50
J 2
(-4800 7900);
DISPLAY 0.468085 (-4800 7900);
PAINT GREEN (-4800 7900);
DISPLAY INVISIBLE (-4800 7900);
FORCEPROP 2 LAST CDS_LIB cls
J 0
(-4800 7900);
DISPLAY INVISIBLE (-4800 7900);
FORCEPROP 1 LAST HDL_POWER SG
J 1
(-4855 7805);
DISPLAY 0.808511 (-4855 7805);
PAINT GREEN (-4855 7805);
FORCEADD CAPACITOR..2
R 2
(-4350 8500);
FORCEPROP 1 LAST $LOCATION C277
J 2
(-4050 8400);
DISPLAY 1.212766 (-4050 8400);
PAINT GREEN (-4050 8400);
FORCEPROP 0 LAST CDS_LOCATION C277
J 0
(-4050 8650);
DISPLAY 1.021277 (-4050 8650);
DISPLAY INVISIBLE (-4050 8650);
FORCEPROP 0 LAST $SEC 1
J 0
(-4050 8650);
DISPLAY 0.680851 (-4050 8650);
PAINT MONO (-4050 8650);
DISPLAY INVISIBLE (-4050 8650);
FORCEPROP 0 LAST CDS_SEC 1
J 0
(-4050 8650);
DISPLAY 1.021277 (-4050 8650);
DISPLAY INVISIBLE (-4050 8650);
FORCEPROP 0 LASTPIN (-4350 8600) $PN 1
R 1
J 0
(-4360 8610);
DISPLAY 0.680851 (-4360 8610);
PAINT MONO (-4360 8610);
FORCEPROP 0 LASTPIN (-4350 8350) $PN 2
R 1
J 2
(-4360 8340);
DISPLAY 0.680851 (-4360 8340);
PAINT MONO (-4360 8340);
FORCEPROP 1 LAST PATH I21
J 2
(-4250 8550);
DISPLAY 1.212766 (-4250 8550);
PAINT GREEN (-4250 8550);
DISPLAY INVISIBLE (-4250 8550);
FORCEPROP 1 LAST TOLERANCE 20%
J 2
(-4200 8600);
DISPLAY 1.212766 (-4200 8600);
PAINT GREEN (-4200 8600);
DISPLAY INVISIBLE (-4200 8600);
FORCEPROP 1 LAST CLS_PN G105-0C106-BM
J 2
(-4250 8550);
DISPLAY 1.212766 (-4250 8550);
PAINT GREEN (-4250 8550);
DISPLAY INVISIBLE (-4250 8550);
FORCEPROP 1 LAST CDS_LMAN_SYM_OUTLINE -50,0,50,-50
J 2
(-4350 8500);
DISPLAY 0.468085 (-4350 8500);
PAINT GREEN (-4350 8500);
DISPLAY INVISIBLE (-4350 8500);
FORCEPROP 2 LAST CDS_LIB passive
J 0
(-4350 8500);
DISPLAY INVISIBLE (-4350 8500);
FORCEPROP 0 LAST VOLTAGE 6.3V
J 0
(-4250 8300);
DISPLAY 1.021277 (-4250 8300);
FORCEPROP 0 LAST PACKAGE 0402
J 0
(-4250 8650);
DISPLAY 1.021277 (-4250 8650);
FORCEPROP 1 LAST VALUE 10UF
J 2
(-4050 8550);
DISPLAY 1.212766 (-4050 8550);
PAINT GREEN (-4050 8550);
FORCEADD VCC..1
(-4900 9100);
FORCEPROP 3 LASTPIN (-4850 9050) SIG_NAME XP1R8V_ICP10100\g
J 0
(-4840 9060);
DISPLAY 0.659574 (-4840 9060);
PAINT MONO (-4840 9060);
DISPLAY INVISIBLE (-4840 9060);
FORCEPROP 1 LAST PATH I22
J 0
(-4865 9190);
DISPLAY 0.808511 (-4865 9190);
PAINT GREEN (-4865 9190);
DISPLAY INVISIBLE (-4865 9190);
FORCEPROP 1 LAST BODY_TYPE PLUMBING
J 0
(-4945 9057);
DISPLAY 0.340426 (-4945 9057);
PAINT GREEN (-4945 9057);
DISPLAY INVISIBLE (-4945 9057);
FORCEPROP 1 LAST CDS_LMAN_SYM_OUTLINE -250,250,250,-250
J 0
(-4900 9100);
DISPLAY 0.468085 (-4900 9100);
PAINT GREEN (-4900 9100);
DISPLAY INVISIBLE (-4900 9100);
FORCEPROP 2 LAST CDS_LIB cls
J 0
(-4900 9100);
DISPLAY INVISIBLE (-4900 9100);
FORCEPROP 1 LAST HDL_POWER XP1R8V_ICP10100
J 1
(-4845 9155);
DISPLAY 1.021277 (-4845 9155);
PAINT GREEN (-4845 9155);
FORCEPROP 0 LAST VOLTAGE 1.8V
J 0
(-5150 9250);
DISPLAY 1.021277 (-5150 9250);
DISPLAY BOTH (-5150 9250);
FORCEADD VCC..1
(-9600 9800);
FORCEPROP 3 LASTPIN (-9550 9750) SIG_NAME XP1R8V_ICP10100\g
J 0
(-9540 9760);
DISPLAY 0.659574 (-9540 9760);
PAINT MONO (-9540 9760);
DISPLAY INVISIBLE (-9540 9760);
FORCEPROP 1 LAST PATH I23
J 0
(-9565 9890);
DISPLAY 0.808511 (-9565 9890);
PAINT GREEN (-9565 9890);
DISPLAY INVISIBLE (-9565 9890);
FORCEPROP 1 LAST BODY_TYPE PLUMBING
J 0
(-9645 9757);
DISPLAY 0.340426 (-9645 9757);
PAINT GREEN (-9645 9757);
DISPLAY INVISIBLE (-9645 9757);
FORCEPROP 2 LAST CDS_LIB cls
J 0
(-9600 9800);
DISPLAY INVISIBLE (-9600 9800);
FORCEPROP 1 LAST CDS_LMAN_SYM_OUTLINE -250,250,250,-250
J 0
(-9600 9800);
DISPLAY 0.468085 (-9600 9800);
PAINT GREEN (-9600 9800);
DISPLAY INVISIBLE (-9600 9800);
FORCEPROP 1 LAST HDL_POWER XP1R8V_ICP10100
J 1
(-9545 9855);
DISPLAY 1.021277 (-9545 9855);
PAINT GREEN (-9545 9855);
FORCEPROP 0 LAST VOLTAGE 1.8V
J 0
(-9700 9950);
DISPLAY 1.021277 (-9700 9950);
DISPLAY BOTH (-9700 9950);
FORCEADD ICP_10100_LGA10..1
R 2
(-5900 8950);
FORCEPROP 2 LASTPIN (-5800 8450) SIG_NAME UN$8$ICP10100LGA10$I24$RESV3
J 0
(-5790 8460);
DISPLAY 0.659574 (-5790 8460);
PAINT MONO (-5790 8460);
DISPLAY INVISIBLE (-5790 8460);
FORCEPROP 2 LASTPIN (-5800 8650) SIG_NAME UN$8$ICP10100LGA10$I24$RESV1
J 0
(-5790 8660);
DISPLAY 0.659574 (-5790 8660);
PAINT MONO (-5790 8660);
DISPLAY INVISIBLE (-5790 8660);
FORCEPROP 2 LASTPIN (-5800 8550) SIG_NAME UN$8$ICP10100LGA10$I24$RESV2
J 0
(-5790 8560);
DISPLAY 0.659574 (-5790 8560);
PAINT MONO (-5790 8560);
DISPLAY INVISIBLE (-5790 8560);
FORCEPROP 2 LASTPIN (-5800 8250) SIG_NAME UN$8$ICP10100LGA10$I24$RESV5
J 0
(-5790 8260);
DISPLAY 0.659574 (-5790 8260);
PAINT MONO (-5790 8260);
DISPLAY INVISIBLE (-5790 8260);
FORCEPROP 2 LASTPIN (-5800 8350) SIG_NAME UN$8$ICP10100LGA10$I24$RESV4
J 0
(-5790 8360);
DISPLAY 0.659574 (-5790 8360);
PAINT MONO (-5790 8360);
DISPLAY INVISIBLE (-5790 8360);
FORCEPROP 1 LAST $LOCATION U28
J 2
(-5950 9050);
DISPLAY 1.212766 (-5950 9050);
PAINT GREEN (-5950 9050);
FORCEPROP 0 LAST CDS_LOCATION U28
J 0
(-5950 9350);
DISPLAY 1.021277 (-5950 9350);
DISPLAY INVISIBLE (-5950 9350);
FORCEPROP 0 LAST $SEC 1
J 0
(-5950 9350);
DISPLAY 0.680851 (-5950 9350);
PAINT MONO (-5950 9350);
DISPLAY INVISIBLE (-5950 9350);
FORCEPROP 0 LAST CDS_SEC 1
J 0
(-5950 9350);
DISPLAY 1.021277 (-5950 9350);
DISPLAY INVISIBLE (-5950 9350);
FORCEPROP 0 LASTPIN (-6750 8350) $PN 8
J 2
(-6760 8360);
DISPLAY 0.680851 (-6760 8360);
PAINT MONO (-6760 8360);
FORCEPROP 0 LASTPIN (-6750 8250) $PN 9
J 2
(-6760 8260);
DISPLAY 0.680851 (-6760 8260);
PAINT MONO (-6760 8260);
FORCEPROP 0 LASTPIN (-5800 8650) $PN 1
J 0
(-5790 8660);
DISPLAY 0.680851 (-5790 8660);
PAINT MONO (-5790 8660);
FORCEPROP 0 LASTPIN (-5800 8550) $PN 3
J 0
(-5790 8560);
DISPLAY 0.680851 (-5790 8560);
PAINT MONO (-5790 8560);
FORCEPROP 0 LASTPIN (-5800 8450) $PN 5
J 0
(-5790 8460);
DISPLAY 0.680851 (-5790 8460);
PAINT MONO (-5790 8460);
FORCEPROP 0 LASTPIN (-5800 8350) $PN 6
J 0
(-5790 8360);
DISPLAY 0.680851 (-5790 8360);
PAINT MONO (-5790 8360);
FORCEPROP 0 LASTPIN (-5800 8250) $PN 7
J 0
(-5790 8260);
DISPLAY 0.680851 (-5790 8260);
PAINT MONO (-5790 8260);
FORCEPROP 0 LASTPIN (-6750 8750) $PN 2
J 2
(-6760 8760);
DISPLAY 0.680851 (-6760 8760);
PAINT MONO (-6760 8760);
FORCEPROP 0 LASTPIN (-6750 8850) $PN 4
J 2
(-6760 8860);
DISPLAY 0.680851 (-6760 8860);
PAINT MONO (-6760 8860);
FORCEPROP 0 LASTPIN (-5800 8850) $PN 10
J 0
(-5790 8860);
DISPLAY 0.680851 (-5790 8860);
PAINT MONO (-5790 8860);
FORCEPROP 1 LAST PATH I24
J 2
(-5950 9000);
DISPLAY 1.212766 (-5950 9000);
PAINT GREEN (-5950 9000);
DISPLAY INVISIBLE (-5950 9000);
FORCEPROP 2 LAST CDS_LIB analog
J 2
(-5900 8950);
DISPLAY INVISIBLE (-5900 8950);
FORCEPROP 1 LAST CDS_LMAN_SYM_OUTLINE 0,0,750,-800
J 2
(-5900 8950);
DISPLAY 0.468085 (-5900 8950);
PAINT GREEN (-5900 8950);
DISPLAY INVISIBLE (-5900 8950);
FORCEPROP 1 LAST VALUE ICP-10100
J 2
(-5950 9250);
DISPLAY 1.212766 (-5950 9250);
PAINT GREEN (-5950 9250);
FORCEPROP 1 LAST CLS_PN A222-00002-FB
J 2
(-5950 9150);
DISPLAY 1.212766 (-5950 9150);
PAINT GREEN (-5950 9150);
FORCEADD GND_SG..1
R 2
(-6850 8000);
FORCEPROP 3 LASTPIN (-6900 8050) SIG_NAME SG\g
J 0
(-6890 8060);
DISPLAY 0.659574 (-6890 8060);
PAINT MONO (-6890 8060);
DISPLAY INVISIBLE (-6890 8060);
FORCEPROP 1 LAST PATH I25
J 2
(-6885 8000);
DISPLAY 0.808511 (-6885 8000);
PAINT GREEN (-6885 8000);
DISPLAY INVISIBLE (-6885 8000);
FORCEPROP 1 LAST BODY_TYPE PLUMBING
J 2
(-6865 7985);
DISPLAY 0.808511 (-6865 7985);
PAINT GREEN (-6865 7985);
DISPLAY INVISIBLE (-6865 7985);
FORCEPROP 1 LAST CDS_LMAN_SYM_OUTLINE 0,0,100,-50
J 2
(-6850 8000);
DISPLAY 0.468085 (-6850 8000);
PAINT GREEN (-6850 8000);
DISPLAY INVISIBLE (-6850 8000);
FORCEPROP 2 LAST CDS_LIB cls
J 0
(-6850 8000);
DISPLAY INVISIBLE (-6850 8000);
FORCEPROP 1 LAST HDL_POWER SG
J 1
(-6905 7905);
DISPLAY 0.808511 (-6905 7905);
PAINT GREEN (-6905 7905);
FORCEADD RESISTOR..2
(-9550 9400);
FORCEPROP 1 LAST $LOCATION R70
J 0
(-9500 9250);
DISPLAY 1.212766 (-9500 9250);
PAINT GREEN (-9500 9250);
FORCEPROP 0 LAST CDS_LOCATION R70
J 0
(-9500 9500);
DISPLAY 1.021277 (-9500 9500);
DISPLAY INVISIBLE (-9500 9500);
FORCEPROP 0 LAST $SEC 1
J 0
(-9500 9500);
DISPLAY 0.680851 (-9500 9500);
PAINT MONO (-9500 9500);
DISPLAY INVISIBLE (-9500 9500);
FORCEPROP 0 LAST CDS_SEC 1
J 0
(-9500 9500);
DISPLAY 1.021277 (-9500 9500);
DISPLAY INVISIBLE (-9500 9500);
FORCEPROP 0 LASTPIN (-9550 9500) $PN 1
R 1
J 0
(-9560 9510);
DISPLAY 0.680851 (-9560 9510);
PAINT MONO (-9560 9510);
FORCEPROP 0 LASTPIN (-9550 9250) $PN 2
R 1
J 2
(-9560 9240);
DISPLAY 0.680851 (-9560 9240);
PAINT MONO (-9560 9240);
FORCEPROP 1 LAST PATH I3
J 0
(-9747 9505);
DISPLAY 1.212766 (-9747 9505);
PAINT GREEN (-9747 9505);
DISPLAY INVISIBLE (-9747 9505);
FORCEPROP 1 LAST TOLERANCE 1%
J 0
(-9747 9655);
DISPLAY 1.212766 (-9747 9655);
PAINT GREEN (-9747 9655);
DISPLAY INVISIBLE (-9747 9655);
FORCEPROP 2 LAST CDS_LIB passive
J 0
(-9550 9400);
DISPLAY INVISIBLE (-9550 9400);
FORCEPROP 1 LAST CDS_LMAN_SYM_OUTLINE -50,50,50,-100
J 0
(-9550 9400);
DISPLAY 0.468085 (-9550 9400);
PAINT GREEN (-9550 9400);
DISPLAY INVISIBLE (-9550 9400);
FORCEPROP 1 LAST CLS_PN G155-14701-01
J 0
(-9686 9600);
DISPLAY 1.212766 (-9686 9600);
PAINT GREEN (-9686 9600);
DISPLAY INVISIBLE (-9686 9600);
FORCEPROP 0 LAST PACKAGE 0402
J 0
(-9500 9550);
DISPLAY 1.021277 (-9500 9550);
FORCEPROP 1 LAST VALUE 4.7KOHM
J 0
(-9500 9450);
DISPLAY 0.978723 (-9500 9450);
PAINT GREEN (-9500 9450);
FORCEADD RESISTOR..1
(-5350 8250);
FORCEPROP 1 LAST $LOCATION R351
J 2
(-5500 8250);
DISPLAY 1.212766 (-5500 8250);
PAINT GREEN (-5500 8250);
FORCEPROP 0 LAST CDS_LOCATION R351
J 0
(-5150 8350);
DISPLAY 1.021277 (-5150 8350);
DISPLAY INVISIBLE (-5150 8350);
FORCEPROP 0 LAST $SEC 1
J 0
(-5150 8350);
DISPLAY 0.680851 (-5150 8350);
PAINT MONO (-5150 8350);
DISPLAY INVISIBLE (-5150 8350);
FORCEPROP 0 LAST CDS_SEC 1
J 0
(-5150 8350);
DISPLAY 1.021277 (-5150 8350);
DISPLAY INVISIBLE (-5150 8350);
FORCEPROP 0 LASTPIN (-5450 8250) $PN 1
J 2
(-5460 8260);
DISPLAY 0.680851 (-5460 8260);
PAINT MONO (-5460 8260);
FORCEPROP 0 LASTPIN (-5200 8250) $PN 2
J 0
(-5190 8260);
DISPLAY 0.680851 (-5190 8260);
PAINT MONO (-5190 8260);
FORCEPROP 1 LAST PATH I30
J 0
(-5547 8355);
DISPLAY 1.212766 (-5547 8355);
PAINT GREEN (-5547 8355);
DISPLAY INVISIBLE (-5547 8355);
FORCEPROP 1 LAST TOLERANCE -
J 0
(-5547 8505);
DISPLAY 1.212766 (-5547 8505);
PAINT GREEN (-5547 8505);
DISPLAY INVISIBLE (-5547 8505);
FORCEPROP 2 LAST CDS_LIB passive
J 0
(-5350 8250);
DISPLAY INVISIBLE (-5350 8250);
FORCEPROP 1 LAST CDS_LMAN_SYM_OUTLINE -50,50,100,-50
J 0
(-5350 8250);
DISPLAY 0.468085 (-5350 8250);
PAINT GREEN (-5350 8250);
DISPLAY INVISIBLE (-5350 8250);
FORCEPROP 1 LAST CLS_PN G155-100R0-J0
J 0
(-5486 8450);
DISPLAY 1.212766 (-5486 8450);
PAINT GREEN (-5486 8450);
DISPLAY INVISIBLE (-5486 8450);
FORCEPROP 1 LAST VALUE 0OHM
J 0
(-5150 8250);
DISPLAY 1.212766 (-5150 8250);
PAINT GREEN (-5150 8250);
FORCEPROP 0 LAST PACKAGE 0402
J 0
(-5400 8250);
DISPLAY 1.021277 (-5400 8250);
FORCEADD RESISTOR..1
(-5350 8350);
FORCEPROP 1 LAST LOCATION R350
J 2
(-5500 8350);
DISPLAY 1.212766 (-5500 8350);
PAINT GREEN (-5500 8350);
FORCEPROP 0 LAST $SEC 1
J 0
(-5150 8450);
DISPLAY 0.680851 (-5150 8450);
PAINT MONO (-5150 8450);
DISPLAY INVISIBLE (-5150 8450);
FORCEPROP 0 LAST CDS_SEC 1
J 0
(-5150 8450);
DISPLAY 1.021277 (-5150 8450);
DISPLAY INVISIBLE (-5150 8450);
FORCEPROP 0 LASTPIN (-5450 8350) $PN 1
J 2
(-5460 8360);
DISPLAY 0.680851 (-5460 8360);
PAINT MONO (-5460 8360);
FORCEPROP 0 LASTPIN (-5200 8350) $PN 2
J 0
(-5190 8360);
DISPLAY 0.680851 (-5190 8360);
PAINT MONO (-5190 8360);
FORCEPROP 1 LAST PATH I31
J 0
(-5547 8455);
DISPLAY 1.212766 (-5547 8455);
PAINT GREEN (-5547 8455);
DISPLAY INVISIBLE (-5547 8455);
FORCEPROP 1 LAST TOLERANCE -
J 0
(-5547 8605);
DISPLAY 1.212766 (-5547 8605);
PAINT GREEN (-5547 8605);
DISPLAY INVISIBLE (-5547 8605);
FORCEPROP 1 LAST CDS_LMAN_SYM_OUTLINE -50,50,100,-50
J 0
(-5350 8350);
DISPLAY 0.468085 (-5350 8350);
PAINT GREEN (-5350 8350);
DISPLAY INVISIBLE (-5350 8350);
FORCEPROP 2 LAST CDS_LIB passive
J 0
(-5350 8350);
DISPLAY INVISIBLE (-5350 8350);
FORCEPROP 1 LAST CLS_PN G155-100R0-J0
J 0
(-5486 8550);
DISPLAY 1.212766 (-5486 8550);
PAINT GREEN (-5486 8550);
DISPLAY INVISIBLE (-5486 8550);
FORCEPROP 1 LAST VALUE 0OHM
J 0
(-5150 8350);
DISPLAY 1.212766 (-5150 8350);
PAINT GREEN (-5150 8350);
FORCEPROP 0 LAST PACKAGE 0402
J 0
(-5400 8350);
DISPLAY 1.021277 (-5400 8350);
FORCEADD RESISTOR..1
(-5350 8450);
FORCEPROP 1 LAST LOCATION R347
J 2
(-5500 8450);
DISPLAY 1.212766 (-5500 8450);
PAINT GREEN (-5500 8450);
FORCEPROP 0 LAST $SEC 1
J 0
(-5150 8550);
DISPLAY 0.680851 (-5150 8550);
PAINT MONO (-5150 8550);
DISPLAY INVISIBLE (-5150 8550);
FORCEPROP 0 LAST CDS_SEC 1
J 0
(-5150 8550);
DISPLAY 1.021277 (-5150 8550);
DISPLAY INVISIBLE (-5150 8550);
FORCEPROP 0 LASTPIN (-5450 8450) $PN 1
J 2
(-5460 8460);
DISPLAY 0.680851 (-5460 8460);
PAINT MONO (-5460 8460);
FORCEPROP 0 LASTPIN (-5200 8450) $PN 2
J 0
(-5190 8460);
DISPLAY 0.680851 (-5190 8460);
PAINT MONO (-5190 8460);
FORCEPROP 1 LAST PATH I32
J 0
(-5547 8555);
DISPLAY 1.212766 (-5547 8555);
PAINT GREEN (-5547 8555);
DISPLAY INVISIBLE (-5547 8555);
FORCEPROP 1 LAST TOLERANCE -
J 0
(-5547 8705);
DISPLAY 1.212766 (-5547 8705);
PAINT GREEN (-5547 8705);
DISPLAY INVISIBLE (-5547 8705);
FORCEPROP 1 LAST CDS_LMAN_SYM_OUTLINE -50,50,100,-50
J 0
(-5350 8450);
DISPLAY 0.468085 (-5350 8450);
PAINT GREEN (-5350 8450);
DISPLAY INVISIBLE (-5350 8450);
FORCEPROP 2 LAST CDS_LIB passive
J 0
(-5350 8450);
DISPLAY INVISIBLE (-5350 8450);
FORCEPROP 1 LAST CLS_PN G155-100R0-J0
J 0
(-5486 8650);
DISPLAY 1.212766 (-5486 8650);
PAINT GREEN (-5486 8650);
DISPLAY INVISIBLE (-5486 8650);
FORCEPROP 1 LAST VALUE 0OHM
J 0
(-5150 8450);
DISPLAY 1.212766 (-5150 8450);
PAINT GREEN (-5150 8450);
FORCEPROP 0 LAST PACKAGE 0402
J 0
(-5400 8450);
DISPLAY 1.021277 (-5400 8450);
FORCEADD RESISTOR..1
(-5350 8550);
FORCEPROP 1 LAST LOCATION R346
J 2
(-5500 8550);
DISPLAY 1.212766 (-5500 8550);
PAINT GREEN (-5500 8550);
FORCEPROP 0 LAST $SEC 1
J 0
(-5150 8650);
DISPLAY 0.680851 (-5150 8650);
PAINT MONO (-5150 8650);
DISPLAY INVISIBLE (-5150 8650);
FORCEPROP 0 LAST CDS_SEC 1
J 0
(-5150 8650);
DISPLAY 1.021277 (-5150 8650);
DISPLAY INVISIBLE (-5150 8650);
FORCEPROP 0 LASTPIN (-5450 8550) $PN 1
J 2
(-5460 8560);
DISPLAY 0.680851 (-5460 8560);
PAINT MONO (-5460 8560);
FORCEPROP 0 LASTPIN (-5200 8550) $PN 2
J 0
(-5190 8560);
DISPLAY 0.680851 (-5190 8560);
PAINT MONO (-5190 8560);
FORCEPROP 1 LAST PATH I33
J 0
(-5547 8655);
DISPLAY 1.212766 (-5547 8655);
PAINT GREEN (-5547 8655);
DISPLAY INVISIBLE (-5547 8655);
FORCEPROP 1 LAST TOLERANCE -
J 0
(-5547 8805);
DISPLAY 1.212766 (-5547 8805);
PAINT GREEN (-5547 8805);
DISPLAY INVISIBLE (-5547 8805);
FORCEPROP 1 LAST CDS_LMAN_SYM_OUTLINE -50,50,100,-50
J 0
(-5350 8550);
DISPLAY 0.468085 (-5350 8550);
PAINT GREEN (-5350 8550);
DISPLAY INVISIBLE (-5350 8550);
FORCEPROP 2 LAST CDS_LIB passive
J 0
(-5350 8550);
DISPLAY INVISIBLE (-5350 8550);
FORCEPROP 1 LAST CLS_PN G155-100R0-J0
J 0
(-5486 8750);
DISPLAY 1.212766 (-5486 8750);
PAINT GREEN (-5486 8750);
DISPLAY INVISIBLE (-5486 8750);
FORCEPROP 1 LAST VALUE 0OHM
J 0
(-5150 8550);
DISPLAY 1.212766 (-5150 8550);
PAINT GREEN (-5150 8550);
FORCEPROP 0 LAST PACKAGE 0402
J 0
(-5400 8550);
DISPLAY 1.021277 (-5400 8550);
FORCEADD RESISTOR..1
(-5350 8650);
FORCEPROP 1 LAST LOCATION R343
J 2
(-5500 8650);
DISPLAY 1.212766 (-5500 8650);
PAINT GREEN (-5500 8650);
FORCEPROP 0 LAST $SEC 1
J 0
(-5150 8750);
DISPLAY 0.680851 (-5150 8750);
PAINT MONO (-5150 8750);
DISPLAY INVISIBLE (-5150 8750);
FORCEPROP 0 LAST CDS_SEC 1
J 0
(-5150 8750);
DISPLAY 1.021277 (-5150 8750);
DISPLAY INVISIBLE (-5150 8750);
FORCEPROP 0 LASTPIN (-5450 8650) $PN 1
J 2
(-5460 8660);
DISPLAY 0.680851 (-5460 8660);
PAINT MONO (-5460 8660);
FORCEPROP 0 LASTPIN (-5200 8650) $PN 2
J 0
(-5190 8660);
DISPLAY 0.680851 (-5190 8660);
PAINT MONO (-5190 8660);
FORCEPROP 1 LAST PATH I34
J 0
(-5547 8755);
DISPLAY 1.212766 (-5547 8755);
PAINT GREEN (-5547 8755);
DISPLAY INVISIBLE (-5547 8755);
FORCEPROP 1 LAST TOLERANCE -
J 0
(-5547 8905);
DISPLAY 1.212766 (-5547 8905);
PAINT GREEN (-5547 8905);
DISPLAY INVISIBLE (-5547 8905);
FORCEPROP 1 LAST CDS_LMAN_SYM_OUTLINE -50,50,100,-50
J 0
(-5350 8650);
DISPLAY 0.468085 (-5350 8650);
PAINT GREEN (-5350 8650);
DISPLAY INVISIBLE (-5350 8650);
FORCEPROP 2 LAST CDS_LIB passive
J 0
(-5350 8650);
DISPLAY INVISIBLE (-5350 8650);
FORCEPROP 1 LAST CLS_PN G155-100R0-J0
J 0
(-5486 8850);
DISPLAY 1.212766 (-5486 8850);
PAINT GREEN (-5486 8850);
DISPLAY INVISIBLE (-5486 8850);
FORCEPROP 1 LAST VALUE 0OHM
J 0
(-5150 8650);
DISPLAY 1.212766 (-5150 8650);
PAINT GREEN (-5150 8650);
FORCEPROP 0 LAST PACKAGE 0402
J 0
(-5400 8650);
DISPLAY 1.021277 (-5400 8650);
FORCEADD GND_SG..1
(-4600 5400);
FORCEPROP 3 LASTPIN (-4550 5450) SIG_NAME SG\g
J 0
(-4540 5460);
DISPLAY 0.659574 (-4540 5460);
PAINT MONO (-4540 5460);
DISPLAY INVISIBLE (-4540 5460);
FORCEPROP 1 LAST PATH I35
J 0
(-4565 5400);
DISPLAY 0.808511 (-4565 5400);
PAINT GREEN (-4565 5400);
DISPLAY INVISIBLE (-4565 5400);
FORCEPROP 1 LAST BODY_TYPE PLUMBING
J 0
(-4585 5385);
DISPLAY 0.808511 (-4585 5385);
PAINT GREEN (-4585 5385);
DISPLAY INVISIBLE (-4585 5385);
FORCEPROP 1 LAST CDS_LMAN_SYM_OUTLINE 0,0,100,-50
J 0
(-4600 5400);
DISPLAY 0.468085 (-4600 5400);
PAINT GREEN (-4600 5400);
DISPLAY INVISIBLE (-4600 5400);
FORCEPROP 2 LAST CDS_LIB cls
J 0
(-4600 5400);
DISPLAY INVISIBLE (-4600 5400);
FORCEPROP 1 LAST HDL_POWER SG
J 1
(-4545 5305);
DISPLAY 0.808511 (-4545 5305);
PAINT GREEN (-4545 5305);
FORCEADD GND_SG..1
(-3850 5400);
FORCEPROP 3 LASTPIN (-3800 5450) SIG_NAME SG\g
J 0
(-3790 5460);
DISPLAY 0.659574 (-3790 5460);
PAINT MONO (-3790 5460);
DISPLAY INVISIBLE (-3790 5460);
FORCEPROP 1 LAST PATH I38
J 0
(-3815 5400);
DISPLAY 0.808511 (-3815 5400);
PAINT GREEN (-3815 5400);
DISPLAY INVISIBLE (-3815 5400);
FORCEPROP 1 LAST BODY_TYPE PLUMBING
J 0
(-3835 5385);
DISPLAY 0.808511 (-3835 5385);
PAINT GREEN (-3835 5385);
DISPLAY INVISIBLE (-3835 5385);
FORCEPROP 2 LAST CDS_LIB cls
J 0
(-3850 5400);
DISPLAY INVISIBLE (-3850 5400);
FORCEPROP 1 LAST CDS_LMAN_SYM_OUTLINE 0,0,100,-50
J 0
(-3850 5400);
DISPLAY 0.468085 (-3850 5400);
PAINT GREEN (-3850 5400);
DISPLAY INVISIBLE (-3850 5400);
FORCEPROP 1 LAST HDL_POWER SG
J 1
(-3795 5305);
DISPLAY 0.808511 (-3795 5305);
PAINT GREEN (-3795 5305);
FORCEADD CAPACITOR..2
(-4550 5700);
FORCEPROP 1 LAST $LOCATION C312
J 0
(-4500 5550);
DISPLAY 1.212766 (-4500 5550);
PAINT GREEN (-4500 5550);
FORCEPROP 0 LAST CDS_LOCATION C312
J 0
(-4500 5850);
DISPLAY 1.021277 (-4500 5850);
DISPLAY INVISIBLE (-4500 5850);
FORCEPROP 0 LAST $SEC 1
J 0
(-4500 5850);
DISPLAY 0.680851 (-4500 5850);
PAINT MONO (-4500 5850);
DISPLAY INVISIBLE (-4500 5850);
FORCEPROP 0 LAST CDS_SEC 1
J 0
(-4500 5850);
DISPLAY 1.021277 (-4500 5850);
DISPLAY INVISIBLE (-4500 5850);
FORCEPROP 0 LASTPIN (-4550 5800) $PN 1
R 1
J 0
(-4560 5810);
DISPLAY 0.680851 (-4560 5810);
PAINT MONO (-4560 5810);
FORCEPROP 0 LASTPIN (-4550 5550) $PN 2
R 1
J 2
(-4560 5540);
DISPLAY 0.680851 (-4560 5540);
PAINT MONO (-4560 5540);
FORCEPROP 1 LAST PATH I39
J 0
(-4650 5750);
DISPLAY 1.212766 (-4650 5750);
PAINT GREEN (-4650 5750);
DISPLAY INVISIBLE (-4650 5750);
FORCEPROP 2 LAST CDS_LIB passive
J 0
(-4550 5700);
DISPLAY INVISIBLE (-4550 5700);
FORCEPROP 1 LAST CDS_LMAN_SYM_OUTLINE -50,0,50,-50
J 0
(-4550 5700);
DISPLAY 0.468085 (-4550 5700);
PAINT GREEN (-4550 5700);
DISPLAY INVISIBLE (-4550 5700);
FORCEPROP 1 LAST CLS_PN G105-0B104-CK
J 0
(-4650 5750);
DISPLAY 1.212766 (-4650 5750);
PAINT GREEN (-4650 5750);
DISPLAY INVISIBLE (-4650 5750);
FORCEPROP 1 LAST TOLERANCE 10%
J 0
(-4700 5800);
DISPLAY 1.212766 (-4700 5800);
PAINT GREEN (-4700 5800);
DISPLAY INVISIBLE (-4700 5800);
FORCEPROP 0 LAST PACKAGE 0402
J 0
(-4500 5850);
DISPLAY 1.021277 (-4500 5850);
FORCEPROP 1 LAST VALUE 0.1UF
J 0
(-4500 5750);
DISPLAY 1.212766 (-4500 5750);
PAINT GREEN (-4500 5750);
FORCEPROP 0 LAST VOLTAGE 10V
J 0
(-4450 5650);
DISPLAY 1.021277 (-4450 5650);
FORCEADD CAPACITOR..2
(-3800 5700);
FORCEPROP 1 LAST $LOCATION C313
J 0
(-3750 5550);
DISPLAY 1.212766 (-3750 5550);
PAINT GREEN (-3750 5550);
FORCEPROP 0 LAST CDS_LOCATION C313
J 0
(-3750 5850);
DISPLAY 1.021277 (-3750 5850);
DISPLAY INVISIBLE (-3750 5850);
FORCEPROP 0 LAST $SEC 1
J 0
(-3750 5850);
DISPLAY 0.680851 (-3750 5850);
PAINT MONO (-3750 5850);
DISPLAY INVISIBLE (-3750 5850);
FORCEPROP 0 LAST CDS_SEC 1
J 0
(-3750 5850);
DISPLAY 1.021277 (-3750 5850);
DISPLAY INVISIBLE (-3750 5850);
FORCEPROP 0 LASTPIN (-3800 5800) $PN 1
R 1
J 0
(-3810 5810);
DISPLAY 0.680851 (-3810 5810);
PAINT MONO (-3810 5810);
FORCEPROP 0 LASTPIN (-3800 5550) $PN 2
R 1
J 2
(-3810 5540);
DISPLAY 0.680851 (-3810 5540);
PAINT MONO (-3810 5540);
FORCEPROP 1 LAST PATH I41
J 0
(-3900 5750);
DISPLAY 1.212766 (-3900 5750);
PAINT GREEN (-3900 5750);
DISPLAY INVISIBLE (-3900 5750);
FORCEPROP 2 LAST CDS_LIB passive
J 0
(-3800 5700);
DISPLAY INVISIBLE (-3800 5700);
FORCEPROP 1 LAST CDS_LMAN_SYM_OUTLINE -50,0,50,-50
J 0
(-3800 5700);
DISPLAY 0.468085 (-3800 5700);
PAINT GREEN (-3800 5700);
DISPLAY INVISIBLE (-3800 5700);
FORCEPROP 1 LAST TOLERANCE 10%
J 0
(-3950 5800);
DISPLAY 1.212766 (-3950 5800);
PAINT GREEN (-3950 5800);
DISPLAY INVISIBLE (-3950 5800);
FORCEPROP 1 LAST CLS_PN G105-0B104-CK
J 0
(-3900 5750);
DISPLAY 1.212766 (-3900 5750);
PAINT GREEN (-3900 5750);
DISPLAY INVISIBLE (-3900 5750);
FORCEPROP 0 LAST PACKAGE 0402
J 0
(-3750 5850);
DISPLAY 1.021277 (-3750 5850);
FORCEPROP 1 LAST VALUE 0.1UF
J 0
(-3750 5750);
DISPLAY 1.212766 (-3750 5750);
PAINT GREEN (-3750 5750);
FORCEPROP 0 LAST VOLTAGE 10V
J 0
(-3700 5650);
DISPLAY 1.021277 (-3700 5650);
FORCEADD OFFPAGE_BI..1
R 2
(-11500 6050);
FORCEPROP 2 LAST $XR0 16D12> 
J 0
(-11719 6050);
DISPLAY 0.638298 (-11719 6050);
PAINT MONO (-11719 6050);
FORCEPROP 2 LAST PATH I43
J 0
(-11450 6150);
DISPLAY 1.021277 (-11450 6150);
DISPLAY INVISIBLE (-11450 6150);
FORCEPROP 1 LAST OFFPAGE TRUE
J 2
(-11510 6105);
DISPLAY 0.808511 (-11510 6105);
PAINT GREEN (-11510 6105);
DISPLAY INVISIBLE (-11510 6105);
FORCEPROP 1 LAST BODY_TYPE COMMENT
J 2
(-11510 6185);
DISPLAY 0.808511 (-11510 6185);
PAINT GREEN (-11510 6185);
DISPLAY INVISIBLE (-11510 6185);
FORCEPROP 1 LAST CDS_LMAN_SYM_OUTLINE -50,50,50,-50
J 2
(-11500 6050);
DISPLAY 0.468085 (-11500 6050);
PAINT GREEN (-11500 6050);
DISPLAY INVISIBLE (-11500 6050);
FORCEPROP 2 LAST CDS_LIB cls
J 0
(-11500 6050);
DISPLAY INVISIBLE (-11500 6050);
FORCEADD OFFPAGE_BI..1
R 2
(-11500 6150);
FORCEPROP 2 LAST $XR0 16D12<> 
J 0
(-11750 6150);
DISPLAY 0.638298 (-11750 6150);
PAINT MONO (-11750 6150);
FORCEPROP 2 LAST PATH I44
J 0
(-11450 6250);
DISPLAY 1.021277 (-11450 6250);
DISPLAY INVISIBLE (-11450 6250);
FORCEPROP 1 LAST OFFPAGE TRUE
J 2
(-11510 6205);
DISPLAY 0.808511 (-11510 6205);
PAINT GREEN (-11510 6205);
DISPLAY INVISIBLE (-11510 6205);
FORCEPROP 1 LAST BODY_TYPE COMMENT
J 2
(-11510 6285);
DISPLAY 0.808511 (-11510 6285);
PAINT GREEN (-11510 6285);
DISPLAY INVISIBLE (-11510 6285);
FORCEPROP 1 LAST CDS_LMAN_SYM_OUTLINE -50,50,50,-50
J 2
(-11500 6150);
DISPLAY 0.468085 (-11500 6150);
PAINT GREEN (-11500 6150);
DISPLAY INVISIBLE (-11500 6150);
FORCEPROP 2 LAST CDS_LIB cls
J 0
(-11500 6150);
DISPLAY INVISIBLE (-11500 6150);
FORCEADD RESISTOR..2
(-9100 9400);
FORCEPROP 1 LAST $LOCATION R71
J 0
(-9050 9250);
DISPLAY 1.212766 (-9050 9250);
PAINT GREEN (-9050 9250);
FORCEPROP 0 LAST CDS_LOCATION R71
J 0
(-9050 9500);
DISPLAY 1.021277 (-9050 9500);
DISPLAY INVISIBLE (-9050 9500);
FORCEPROP 0 LAST $SEC 1
J 0
(-9050 9500);
DISPLAY 0.680851 (-9050 9500);
PAINT MONO (-9050 9500);
DISPLAY INVISIBLE (-9050 9500);
FORCEPROP 0 LAST CDS_SEC 1
J 0
(-9050 9500);
DISPLAY 1.021277 (-9050 9500);
DISPLAY INVISIBLE (-9050 9500);
FORCEPROP 0 LASTPIN (-9100 9500) $PN 1
R 1
J 0
(-9110 9510);
DISPLAY 0.680851 (-9110 9510);
PAINT MONO (-9110 9510);
FORCEPROP 0 LASTPIN (-9100 9250) $PN 2
R 1
J 2
(-9110 9240);
DISPLAY 0.680851 (-9110 9240);
PAINT MONO (-9110 9240);
FORCEPROP 1 LAST PATH I5
J 0
(-9297 9505);
DISPLAY 1.212766 (-9297 9505);
PAINT GREEN (-9297 9505);
DISPLAY INVISIBLE (-9297 9505);
FORCEPROP 1 LAST TOLERANCE 1%
J 0
(-9297 9655);
DISPLAY 1.212766 (-9297 9655);
PAINT GREEN (-9297 9655);
DISPLAY INVISIBLE (-9297 9655);
FORCEPROP 2 LAST CDS_LIB passive
J 0
(-9100 9400);
DISPLAY INVISIBLE (-9100 9400);
FORCEPROP 1 LAST CDS_LMAN_SYM_OUTLINE -50,50,50,-100
J 0
(-9100 9400);
DISPLAY 0.468085 (-9100 9400);
PAINT GREEN (-9100 9400);
DISPLAY INVISIBLE (-9100 9400);
FORCEPROP 1 LAST CLS_PN G155-14701-01
J 0
(-9236 9600);
DISPLAY 1.212766 (-9236 9600);
PAINT GREEN (-9236 9600);
DISPLAY INVISIBLE (-9236 9600);
FORCEPROP 1 LAST VALUE 4.7KOHM
J 0
(-9050 9450);
DISPLAY 0.978723 (-9050 9450);
PAINT GREEN (-9050 9450);
FORCEPROP 0 LAST PACKAGE 0402
J 0
(-9050 9550);
DISPLAY 1.021277 (-9050 9550);
FORCEADD PCA9508DP_TSSOP8..1
(-8600 6250);
FORCEPROP 1 LAST $LOCATION U32
J 0
(-8600 6400);
DISPLAY 1.212766 (-8600 6400);
PAINT GREEN (-8600 6400);
FORCEPROP 0 LAST CDS_LOCATION U32
J 0
(-8600 6500);
DISPLAY 1.021277 (-8600 6500);
DISPLAY INVISIBLE (-8600 6500);
FORCEPROP 0 LAST $SEC 1
J 0
(-8600 6500);
DISPLAY 0.680851 (-8600 6500);
PAINT MONO (-8600 6500);
DISPLAY INVISIBLE (-8600 6500);
FORCEPROP 0 LAST CDS_SEC 1
J 0
(-8600 6500);
DISPLAY 1.021277 (-8600 6500);
DISPLAY INVISIBLE (-8600 6500);
FORCEPROP 0 LASTPIN (-8700 5850) $PN 5
J 2
(-8710 5860);
DISPLAY 0.680851 (-8710 5860);
PAINT MONO (-8710 5860);
FORCEPROP 0 LASTPIN (-7900 6050) $PN 2
J 0
(-7890 6060);
DISPLAY 0.680851 (-7890 6060);
PAINT MONO (-7890 6060);
FORCEPROP 0 LASTPIN (-8700 6050) $PN 7
J 2
(-8710 6060);
DISPLAY 0.680851 (-8710 6060);
PAINT MONO (-8710 6060);
FORCEPROP 0 LASTPIN (-7900 6150) $PN 3
J 0
(-7890 6160);
DISPLAY 0.680851 (-7890 6160);
PAINT MONO (-7890 6160);
FORCEPROP 0 LASTPIN (-8700 6150) $PN 6
J 2
(-8710 6160);
DISPLAY 0.680851 (-8710 6160);
PAINT MONO (-8710 6160);
FORCEPROP 1 LAST PATH I51
J 0
(-8550 6300);
DISPLAY 1.212766 (-8550 6300);
PAINT GREEN (-8550 6300);
DISPLAY INVISIBLE (-8550 6300);
FORCEPROP 2 LASTPIN (-8700 5850) SIG_NAME UN$8$PCA9508DPTSSOP8$I51$EN
J 0
(-8690 5860);
DISPLAY 0.659574 (-8690 5860);
PAINT MONO (-8690 5860);
DISPLAY INVISIBLE (-8690 5860);
FORCEPROP 2 LAST CDS_LIB stdlogic
J 2
(-8600 6250);
DISPLAY INVISIBLE (-8600 6250);
FORCEPROP 1 LAST CDS_LMAN_SYM_OUTLINE 0,0,600,-450
J 0
(-8600 6250);
DISPLAY 0.468085 (-8600 6250);
PAINT GREEN (-8600 6250);
DISPLAY INVISIBLE (-8600 6250);
FORCEPROP 1 LAST CLS_PN G223-10278-01
J 0
(-8600 6300);
DISPLAY 1.212766 (-8600 6300);
PAINT GREEN (-8600 6300);
FORCEADD PCA9508DP_TSSOP8..2
R 1
(-3400 5850);
FORCEPROP 1 LAST $LOCATION U32
J 2
(-2750 6400);
DISPLAY 1.212766 (-2750 6400);
PAINT GREEN (-2750 6400);
FORCEPROP 0 LAST CDS_LOCATION U32
R 1
J 0
(-2750 6500);
DISPLAY 1.021277 (-2750 6500);
DISPLAY INVISIBLE (-2750 6500);
FORCEPROP 0 LAST $SEC 2
R 1
J 0
(-2750 6500);
DISPLAY 0.680851 (-2750 6500);
PAINT MONO (-2750 6500);
DISPLAY INVISIBLE (-2750 6500);
FORCEPROP 0 LAST CDS_SEC 2
R 1
J 0
(-2750 6500);
DISPLAY 1.021277 (-2750 6500);
DISPLAY INVISIBLE (-2750 6500);
FORCEPROP 0 LASTPIN (-2650 5950) $PN 4
J 0
(-2640 5960);
DISPLAY 0.680851 (-2640 5960);
PAINT MONO (-2640 5960);
FORCEPROP 0 LASTPIN (-3500 5950) $PN 1
J 2
(-3510 5960);
DISPLAY 0.680851 (-3510 5960);
PAINT MONO (-3510 5960);
FORCEPROP 0 LASTPIN (-3500 6150) $PN 8
J 2
(-3510 6160);
DISPLAY 0.680851 (-3510 6160);
PAINT MONO (-3510 6160);
FORCEPROP 1 LAST PATH I52
R 1
J 2
(-3450 5800);
DISPLAY 1.212766 (-3450 5800);
PAINT GREEN (-3450 5800);
DISPLAY INVISIBLE (-3450 5800);
FORCEPROP 1 LAST CDS_LMAN_SYM_OUTLINE 0,0,400,-650
R 1
J 0
(-3400 5850);
DISPLAY 0.468085 (-3400 5850);
PAINT GREEN (-3400 5850);
DISPLAY INVISIBLE (-3400 5850);
FORCEPROP 2 LAST CDS_LIB stdlogic
R 1
J 0
(-3400 5850);
DISPLAY INVISIBLE (-3400 5850);
FORCEPROP 1 LAST CLS_PN G223-10278-01
J 2
(-2750 6300);
DISPLAY 1.212766 (-2750 6300);
PAINT GREEN (-2750 6300);
FORCEADD GND_SG..1
(-2500 5550);
FORCEPROP 3 LASTPIN (-2450 5600) SIG_NAME SG\g
J 0
(-2440 5610);
DISPLAY 0.659574 (-2440 5610);
PAINT MONO (-2440 5610);
DISPLAY INVISIBLE (-2440 5610);
FORCEPROP 1 LAST PATH I53
J 0
(-2465 5550);
DISPLAY 0.808511 (-2465 5550);
PAINT GREEN (-2465 5550);
DISPLAY INVISIBLE (-2465 5550);
FORCEPROP 1 LAST BODY_TYPE PLUMBING
J 0
(-2485 5535);
DISPLAY 0.808511 (-2485 5535);
PAINT GREEN (-2485 5535);
DISPLAY INVISIBLE (-2485 5535);
FORCEPROP 1 LAST CDS_LMAN_SYM_OUTLINE 0,0,100,-50
J 0
(-2500 5550);
DISPLAY 0.468085 (-2500 5550);
PAINT GREEN (-2500 5550);
DISPLAY INVISIBLE (-2500 5550);
FORCEPROP 2 LAST CDS_LIB cls
J 0
(-2500 5550);
DISPLAY INVISIBLE (-2500 5550);
FORCEPROP 1 LAST HDL_POWER SG
J 1
(-2445 5455);
DISPLAY 0.808511 (-2445 5455);
PAINT GREEN (-2445 5455);
FORCEADD VCC..1
(-3850 6400);
FORCEPROP 3 LASTPIN (-3800 6350) SIG_NAME XP1R8V_ICP10100\g
J 0
(-3790 6360);
DISPLAY 0.659574 (-3790 6360);
PAINT MONO (-3790 6360);
DISPLAY INVISIBLE (-3790 6360);
FORCEPROP 1 LAST PATH I54
J 0
(-3815 6490);
DISPLAY 0.808511 (-3815 6490);
PAINT GREEN (-3815 6490);
DISPLAY INVISIBLE (-3815 6490);
FORCEPROP 1 LAST BODY_TYPE PLUMBING
J 0
(-3895 6357);
DISPLAY 0.340426 (-3895 6357);
PAINT GREEN (-3895 6357);
DISPLAY INVISIBLE (-3895 6357);
FORCEPROP 2 LAST CDS_LIB cls
J 0
(-3850 6400);
DISPLAY INVISIBLE (-3850 6400);
FORCEPROP 1 LAST CDS_LMAN_SYM_OUTLINE -250,250,250,-250
J 0
(-3850 6400);
DISPLAY 0.468085 (-3850 6400);
PAINT GREEN (-3850 6400);
DISPLAY INVISIBLE (-3850 6400);
FORCEPROP 1 LAST HDL_POWER XP1R8V_ICP10100
J 1
(-3795 6455);
DISPLAY 1.021277 (-3795 6455);
PAINT GREEN (-3795 6455);
FORCEPROP 0 LAST VOLTAGE 1.8V
J 0
(-4100 6550);
DISPLAY 1.021277 (-4100 6550);
DISPLAY BOTH (-4100 6550);
FORCEADD OFFPAGE_BI..1
(-5950 6150);
FORCEPROP 2 LAST $XR0 19D4<> 
J 0
(-5890 6150);
DISPLAY 0.638298 (-5890 6150);
PAINT MONO (-5890 6150);
FORCEPROP 2 LAST PATH I57
J 2
(-5700 6200);
DISPLAY 1.021277 (-5700 6200);
DISPLAY INVISIBLE (-5700 6200);
FORCEPROP 1 LAST OFFPAGE TRUE
J 0
(-5940 6205);
DISPLAY 0.808511 (-5940 6205);
PAINT GREEN (-5940 6205);
DISPLAY INVISIBLE (-5940 6205);
FORCEPROP 2 LAST CDS_LIB cls
J 2
(-5950 6150);
DISPLAY INVISIBLE (-5950 6150);
FORCEPROP 1 LAST CDS_LMAN_SYM_OUTLINE -50,50,50,-50
J 0
(-5950 6150);
DISPLAY 0.468085 (-5950 6150);
PAINT GREEN (-5950 6150);
DISPLAY INVISIBLE (-5950 6150);
FORCEPROP 1 LAST BODY_TYPE COMMENT
J 0
(-5940 6285);
DISPLAY 0.808511 (-5940 6285);
PAINT GREEN (-5940 6285);
DISPLAY INVISIBLE (-5940 6285);
FORCEADD OFFPAGE_OUT..1
(-5950 6050);
FORCEPROP 2 LAST $XR0 19E4< 
J 0
(-5895 6050);
DISPLAY 0.638298 (-5895 6050);
PAINT MONO (-5895 6050);
FORCEPROP 2 LAST PATH I58
J 0
(-5900 6150);
DISPLAY 1.021277 (-5900 6150);
DISPLAY INVISIBLE (-5900 6150);
FORCEPROP 1 LAST OFFPAGE TRUE
J 0
(-5940 6105);
DISPLAY 0.808511 (-5940 6105);
PAINT GREEN (-5940 6105);
DISPLAY INVISIBLE (-5940 6105);
FORCEPROP 2 LAST CDS_LIB cls
J 0
(-5950 6050);
DISPLAY INVISIBLE (-5950 6050);
FORCEPROP 1 LAST CDS_LMAN_SYM_OUTLINE -50,50,50,-50
J 0
(-5950 6050);
DISPLAY 0.468085 (-5950 6050);
PAINT GREEN (-5950 6050);
DISPLAY INVISIBLE (-5950 6050);
FORCEPROP 1 LAST BODY_TYPE COMMENT
J 0
(-5940 6185);
DISPLAY 0.808511 (-5940 6185);
PAINT GREEN (-5940 6185);
DISPLAY INVISIBLE (-5940 6185);
FORCEADD RESISTOR..1
(-8600 8750);
FORCEPROP 1 LAST $LOCATION R73
J 2
(-8800 8750);
DISPLAY 1.212766 (-8800 8750);
PAINT GREEN (-8800 8750);
FORCEPROP 0 LAST CDS_LOCATION R73
J 0
(-8400 8850);
DISPLAY 1.021277 (-8400 8850);
DISPLAY INVISIBLE (-8400 8850);
FORCEPROP 0 LAST $SEC 1
J 0
(-8400 8850);
DISPLAY 0.680851 (-8400 8850);
PAINT MONO (-8400 8850);
DISPLAY INVISIBLE (-8400 8850);
FORCEPROP 0 LAST CDS_SEC 1
J 0
(-8400 8850);
DISPLAY 1.021277 (-8400 8850);
DISPLAY INVISIBLE (-8400 8850);
FORCEPROP 0 LASTPIN (-8700 8750) $PN 1
J 2
(-8710 8760);
DISPLAY 0.680851 (-8710 8760);
PAINT MONO (-8710 8760);
FORCEPROP 0 LASTPIN (-8450 8750) $PN 2
J 0
(-8440 8760);
DISPLAY 0.680851 (-8440 8760);
PAINT MONO (-8440 8760);
FORCEPROP 1 LAST PATH I6
J 0
(-8797 8855);
DISPLAY 1.212766 (-8797 8855);
PAINT GREEN (-8797 8855);
DISPLAY INVISIBLE (-8797 8855);
FORCEPROP 1 LAST TOLERANCE 1%
J 0
(-8797 9005);
DISPLAY 1.212766 (-8797 9005);
PAINT GREEN (-8797 9005);
DISPLAY INVISIBLE (-8797 9005);
FORCEPROP 1 LAST CLS_PN G155-133R0-01
J 0
(-8736 8950);
DISPLAY 1.212766 (-8736 8950);
PAINT GREEN (-8736 8950);
DISPLAY INVISIBLE (-8736 8950);
FORCEPROP 2 LAST SIGNAL_MODEL DEFAULT_RESISTOR_33OHM_2_1
J 0
(-8750 8950);
DISPLAY 1.021277 (-8750 8950);
DISPLAY INVISIBLE (-8750 8950);
FORCEPROP 1 LAST CDS_LMAN_SYM_OUTLINE -50,50,100,-50
J 0
(-8600 8750);
DISPLAY 0.468085 (-8600 8750);
PAINT GREEN (-8600 8750);
DISPLAY INVISIBLE (-8600 8750);
FORCEPROP 2 LAST CDS_LIB passive
J 0
(-8600 8750);
DISPLAY INVISIBLE (-8600 8750);
FORCEPROP 1 LAST VALUE 33OHM
J 0
(-8400 8750);
DISPLAY 1.234043 (-8400 8750);
PAINT GREEN (-8400 8750);
FORCEPROP 0 LAST PACKAGE 0402
J 0
(-8650 8650);
DISPLAY 1.021277 (-8650 8650);
FORCEADD RESISTOR..1
(-8350 5550);
FORCEPROP 1 LAST $LOCATION R315
J 2
(-8550 5550);
DISPLAY 1.212766 (-8550 5550);
PAINT GREEN (-8550 5550);
FORCEPROP 0 LAST CDS_LOCATION R315
J 0
(-8100 5650);
DISPLAY 1.021277 (-8100 5650);
DISPLAY INVISIBLE (-8100 5650);
FORCEPROP 0 LAST $SEC 1
J 0
(-8100 5650);
DISPLAY 0.680851 (-8100 5650);
PAINT MONO (-8100 5650);
DISPLAY INVISIBLE (-8100 5650);
FORCEPROP 0 LAST CDS_SEC 1
J 0
(-8100 5650);
DISPLAY 1.021277 (-8100 5650);
DISPLAY INVISIBLE (-8100 5650);
FORCEPROP 0 LASTPIN (-8450 5550) $PN 1
J 2
(-8460 5560);
DISPLAY 0.680851 (-8460 5560);
PAINT MONO (-8460 5560);
FORCEPROP 0 LASTPIN (-8200 5550) $PN 2
J 0
(-8190 5560);
DISPLAY 0.680851 (-8190 5560);
PAINT MONO (-8190 5560);
FORCEPROP 1 LAST PATH I63
J 0
(-8547 5655);
DISPLAY 1.212766 (-8547 5655);
PAINT GREEN (-8547 5655);
DISPLAY INVISIBLE (-8547 5655);
FORCEPROP 1 LAST TOLERANCE -
J 0
(-8547 5805);
DISPLAY 1.212766 (-8547 5805);
PAINT GREEN (-8547 5805);
DISPLAY INVISIBLE (-8547 5805);
FORCEPROP 2 LAST CDS_LIB passive
J 0
(-8350 5550);
DISPLAY INVISIBLE (-8350 5550);
FORCEPROP 1 LAST CDS_LMAN_SYM_OUTLINE -50,50,100,-50
J 0
(-8350 5550);
DISPLAY 0.468085 (-8350 5550);
PAINT GREEN (-8350 5550);
DISPLAY INVISIBLE (-8350 5550);
FORCEPROP 1 LAST CLS_PN G155-100R0-J0
J 0
(-8486 5750);
DISPLAY 1.212766 (-8486 5750);
PAINT GREEN (-8486 5750);
DISPLAY INVISIBLE (-8486 5750);
FORCEPROP 0 LAST NO_ASSY TRUE
J 0
(-8150 5600);
DISPLAY 1.021277 (-8150 5600);
DISPLAY BOTH (-8150 5600);
FORCEPROP 1 LAST VALUE 0OHM
J 0
(-8100 5550);
DISPLAY 1.212766 (-8100 5550);
PAINT GREEN (-8100 5550);
FORCEPROP 0 LAST PACKAGE 0402
J 0
(-8400 5600);
DISPLAY 1.021277 (-8400 5600);
FORCEADD RESISTOR..1
(-8350 5450);
FORCEPROP 1 LAST $LOCATION R316
J 2
(-8550 5450);
DISPLAY 1.212766 (-8550 5450);
PAINT GREEN (-8550 5450);
FORCEPROP 0 LAST CDS_LOCATION R316
J 0
(-8100 5550);
DISPLAY 1.021277 (-8100 5550);
DISPLAY INVISIBLE (-8100 5550);
FORCEPROP 0 LAST $SEC 1
J 0
(-8100 5550);
DISPLAY 0.680851 (-8100 5550);
PAINT MONO (-8100 5550);
DISPLAY INVISIBLE (-8100 5550);
FORCEPROP 0 LAST CDS_SEC 1
J 0
(-8100 5550);
DISPLAY 1.021277 (-8100 5550);
DISPLAY INVISIBLE (-8100 5550);
FORCEPROP 0 LASTPIN (-8450 5450) $PN 1
J 2
(-8460 5460);
DISPLAY 0.680851 (-8460 5460);
PAINT MONO (-8460 5460);
FORCEPROP 0 LASTPIN (-8200 5450) $PN 2
J 0
(-8190 5460);
DISPLAY 0.680851 (-8190 5460);
PAINT MONO (-8190 5460);
FORCEPROP 1 LAST PATH I64
J 0
(-8547 5555);
DISPLAY 1.212766 (-8547 5555);
PAINT GREEN (-8547 5555);
DISPLAY INVISIBLE (-8547 5555);
FORCEPROP 1 LAST TOLERANCE -
J 0
(-8547 5705);
DISPLAY 1.212766 (-8547 5705);
PAINT GREEN (-8547 5705);
DISPLAY INVISIBLE (-8547 5705);
FORCEPROP 1 LAST CLS_PN G155-100R0-J0
J 0
(-8486 5650);
DISPLAY 1.212766 (-8486 5650);
PAINT GREEN (-8486 5650);
DISPLAY INVISIBLE (-8486 5650);
FORCEPROP 1 LAST CDS_LMAN_SYM_OUTLINE -50,50,100,-50
J 0
(-8350 5450);
DISPLAY 0.468085 (-8350 5450);
PAINT GREEN (-8350 5450);
DISPLAY INVISIBLE (-8350 5450);
FORCEPROP 2 LAST CDS_LIB passive
J 0
(-8350 5450);
DISPLAY INVISIBLE (-8350 5450);
FORCEPROP 0 LAST NO_ASSY TRUE
J 0
(-8150 5350);
DISPLAY 1.021277 (-8150 5350);
DISPLAY BOTH (-8150 5350);
FORCEPROP 1 LAST VALUE 0OHM
J 0
(-8100 5450);
DISPLAY 1.212766 (-8100 5450);
PAINT GREEN (-8100 5450);
FORCEPROP 0 LAST PACKAGE 0402
J 0
(-8400 5350);
DISPLAY 1.021277 (-8400 5350);
FORCEADD RESISTOR..2
(-9550 6600);
FORCEPROP 1 LAST $LOCATION R282
J 0
(-9500 6450);
DISPLAY 1.212766 (-9500 6450);
PAINT GREEN (-9500 6450);
FORCEPROP 0 LAST CDS_LOCATION R282
J 0
(-9500 6800);
DISPLAY 1.021277 (-9500 6800);
DISPLAY INVISIBLE (-9500 6800);
FORCEPROP 0 LAST $SEC 1
J 0
(-9500 6800);
DISPLAY 0.680851 (-9500 6800);
PAINT MONO (-9500 6800);
DISPLAY INVISIBLE (-9500 6800);
FORCEPROP 0 LAST CDS_SEC 1
J 0
(-9500 6800);
DISPLAY 1.021277 (-9500 6800);
DISPLAY INVISIBLE (-9500 6800);
FORCEPROP 0 LASTPIN (-9550 6700) $PN 1
R 1
J 0
(-9560 6710);
DISPLAY 0.680851 (-9560 6710);
PAINT MONO (-9560 6710);
FORCEPROP 0 LASTPIN (-9550 6450) $PN 2
R 1
J 2
(-9560 6440);
DISPLAY 0.680851 (-9560 6440);
PAINT MONO (-9560 6440);
FORCEPROP 1 LAST PATH I69
J 0
(-9747 6705);
DISPLAY 1.212766 (-9747 6705);
PAINT GREEN (-9747 6705);
DISPLAY INVISIBLE (-9747 6705);
FORCEPROP 1 LAST TOLERANCE 1%
J 0
(-9747 6855);
DISPLAY 1.212766 (-9747 6855);
PAINT GREEN (-9747 6855);
DISPLAY INVISIBLE (-9747 6855);
FORCEPROP 1 LAST CLS_PN G155-14701-01
J 0
(-9686 6800);
DISPLAY 1.212766 (-9686 6800);
PAINT GREEN (-9686 6800);
DISPLAY INVISIBLE (-9686 6800);
FORCEPROP 1 LAST CDS_LMAN_SYM_OUTLINE -50,50,50,-100
J 0
(-9550 6600);
DISPLAY 0.468085 (-9550 6600);
PAINT GREEN (-9550 6600);
DISPLAY INVISIBLE (-9550 6600);
FORCEPROP 2 LAST CDS_LIB passive
J 0
(-9550 6600);
DISPLAY INVISIBLE (-9550 6600);
FORCEPROP 0 LAST PACKAGE 0402
J 0
(-9500 6750);
DISPLAY 1.021277 (-9500 6750);
FORCEPROP 1 LAST VALUE 4.7KOHM
J 0
(-9500 6650);
DISPLAY 0.978723 (-9500 6650);
PAINT GREEN (-9500 6650);
FORCEADD RESISTOR..1
(-8600 8850);
FORCEPROP 1 LAST $LOCATION R72
J 2
(-8800 8850);
DISPLAY 1.212766 (-8800 8850);
PAINT GREEN (-8800 8850);
FORCEPROP 0 LAST CDS_LOCATION R72
J 0
(-8400 8950);
DISPLAY 1.021277 (-8400 8950);
DISPLAY INVISIBLE (-8400 8950);
FORCEPROP 0 LAST $SEC 1
J 0
(-8400 8950);
DISPLAY 0.680851 (-8400 8950);
PAINT MONO (-8400 8950);
DISPLAY INVISIBLE (-8400 8950);
FORCEPROP 0 LAST CDS_SEC 1
J 0
(-8400 8950);
DISPLAY 1.021277 (-8400 8950);
DISPLAY INVISIBLE (-8400 8950);
FORCEPROP 0 LASTPIN (-8700 8850) $PN 1
J 2
(-8710 8860);
DISPLAY 0.680851 (-8710 8860);
PAINT MONO (-8710 8860);
FORCEPROP 0 LASTPIN (-8450 8850) $PN 2
J 0
(-8440 8860);
DISPLAY 0.680851 (-8440 8860);
PAINT MONO (-8440 8860);
FORCEPROP 1 LAST PATH I7
J 0
(-8797 8955);
DISPLAY 1.212766 (-8797 8955);
PAINT GREEN (-8797 8955);
DISPLAY INVISIBLE (-8797 8955);
FORCEPROP 1 LAST TOLERANCE 1%
J 0
(-8797 9105);
DISPLAY 1.212766 (-8797 9105);
PAINT GREEN (-8797 9105);
DISPLAY INVISIBLE (-8797 9105);
FORCEPROP 1 LAST CLS_PN G155-133R0-01
J 0
(-8736 9050);
DISPLAY 1.212766 (-8736 9050);
PAINT GREEN (-8736 9050);
DISPLAY INVISIBLE (-8736 9050);
FORCEPROP 2 LAST CDS_LIB passive
J 0
(-8600 8850);
DISPLAY INVISIBLE (-8600 8850);
FORCEPROP 1 LAST CDS_LMAN_SYM_OUTLINE -50,50,100,-50
J 0
(-8600 8850);
DISPLAY 0.468085 (-8600 8850);
PAINT GREEN (-8600 8850);
DISPLAY INVISIBLE (-8600 8850);
FORCEPROP 2 LAST SIGNAL_MODEL DEFAULT_RESISTOR_33OHM_2_1
J 0
(-8750 9050);
DISPLAY 1.021277 (-8750 9050);
DISPLAY INVISIBLE (-8750 9050);
FORCEPROP 1 LAST VALUE 33OHM
J 0
(-8400 8850);
DISPLAY 1.234043 (-8400 8850);
PAINT GREEN (-8400 8850);
FORCEPROP 0 LAST PACKAGE 0402
J 0
(-8650 8900);
DISPLAY 1.021277 (-8650 8900);
FORCEADD RESISTOR..2
(-10000 6600);
FORCEPROP 1 LAST $LOCATION R281
J 0
(-9950 6450);
DISPLAY 1.212766 (-9950 6450);
PAINT GREEN (-9950 6450);
FORCEPROP 0 LAST CDS_LOCATION R281
J 0
(-9950 6800);
DISPLAY 1.021277 (-9950 6800);
DISPLAY INVISIBLE (-9950 6800);
FORCEPROP 0 LAST $SEC 1
J 0
(-9950 6800);
DISPLAY 0.680851 (-9950 6800);
PAINT MONO (-9950 6800);
DISPLAY INVISIBLE (-9950 6800);
FORCEPROP 0 LAST CDS_SEC 1
J 0
(-9950 6800);
DISPLAY 1.021277 (-9950 6800);
DISPLAY INVISIBLE (-9950 6800);
FORCEPROP 0 LASTPIN (-10000 6700) $PN 1
R 1
J 0
(-10010 6710);
DISPLAY 0.680851 (-10010 6710);
PAINT MONO (-10010 6710);
FORCEPROP 0 LASTPIN (-10000 6450) $PN 2
R 1
J 2
(-10010 6440);
DISPLAY 0.680851 (-10010 6440);
PAINT MONO (-10010 6440);
FORCEPROP 1 LAST PATH I70
J 0
(-10197 6705);
DISPLAY 1.212766 (-10197 6705);
PAINT GREEN (-10197 6705);
DISPLAY INVISIBLE (-10197 6705);
FORCEPROP 1 LAST TOLERANCE 1%
J 0
(-10197 6855);
DISPLAY 1.212766 (-10197 6855);
PAINT GREEN (-10197 6855);
DISPLAY INVISIBLE (-10197 6855);
FORCEPROP 1 LAST CLS_PN G155-14701-01
J 0
(-10136 6800);
DISPLAY 1.212766 (-10136 6800);
PAINT GREEN (-10136 6800);
DISPLAY INVISIBLE (-10136 6800);
FORCEPROP 1 LAST CDS_LMAN_SYM_OUTLINE -50,50,50,-100
J 0
(-10000 6600);
DISPLAY 0.468085 (-10000 6600);
PAINT GREEN (-10000 6600);
DISPLAY INVISIBLE (-10000 6600);
FORCEPROP 2 LAST CDS_LIB passive
J 0
(-10000 6600);
DISPLAY INVISIBLE (-10000 6600);
FORCEPROP 1 LAST VALUE 4.7KOHM
J 0
(-9950 6650);
DISPLAY 0.978723 (-9950 6650);
PAINT GREEN (-9950 6650);
FORCEPROP 0 LAST PACKAGE 0402
J 0
(-9950 6750);
DISPLAY 1.021277 (-9950 6750);
FORCEADD RESISTOR..1
R 3
(-9100 6650);
FORCEPROP 1 LAST $LOCATION R314
J 2
(-8800 6450);
DISPLAY 1.212766 (-8800 6450);
PAINT GREEN (-8800 6450);
FORCEPROP 0 LAST CDS_LOCATION R314
R 1
J 2
(-9200 6400);
DISPLAY 1.021277 (-9200 6400);
DISPLAY INVISIBLE (-9200 6400);
FORCEPROP 0 LAST $SEC 1
R 1
J 2
(-9200 6400);
DISPLAY 0.680851 (-9200 6400);
PAINT MONO (-9200 6400);
DISPLAY INVISIBLE (-9200 6400);
FORCEPROP 0 LAST CDS_SEC 1
R 1
J 2
(-9200 6400);
DISPLAY 1.021277 (-9200 6400);
DISPLAY INVISIBLE (-9200 6400);
FORCEPROP 0 LASTPIN (-9100 6750) $PN 1
R 1
J 0
(-9110 6760);
DISPLAY 0.680851 (-9110 6760);
PAINT MONO (-9110 6760);
FORCEPROP 0 LASTPIN (-9100 6500) $PN 2
R 1
J 2
(-9110 6490);
DISPLAY 0.680851 (-9110 6490);
PAINT MONO (-9110 6490);
FORCEPROP 1 LAST PATH I71
R 1
J 2
(-9205 6847);
DISPLAY 1.212766 (-9205 6847);
PAINT GREEN (-9205 6847);
DISPLAY INVISIBLE (-9205 6847);
FORCEPROP 1 LAST TOLERANCE 1%
R 1
J 2
(-9355 6847);
DISPLAY 1.212766 (-9355 6847);
PAINT GREEN (-9355 6847);
DISPLAY INVISIBLE (-9355 6847);
FORCEPROP 2 LAST CDS_LIB passive
R 1
J 2
(-9100 6650);
DISPLAY INVISIBLE (-9100 6650);
FORCEPROP 1 LAST CDS_LMAN_SYM_OUTLINE -50,50,100,-50
R 1
J 2
(-9100 6650);
DISPLAY 0.468085 (-9100 6650);
PAINT GREEN (-9100 6650);
DISPLAY INVISIBLE (-9100 6650);
FORCEPROP 1 LAST CLS_PN G155-14701-01
R 1
J 2
(-9300 6786);
DISPLAY 1.212766 (-9300 6786);
PAINT GREEN (-9300 6786);
DISPLAY INVISIBLE (-9300 6786);
FORCEPROP 1 LAST VALUE 4.7KOHM
J 0
(-9000 6650);
DISPLAY 1.212766 (-9000 6650);
PAINT GREEN (-9000 6650);
FORCEPROP 0 LAST PACKAGE 0402
J 0
(-9000 6750);
DISPLAY 1.021277 (-9000 6750);
FORCEADD VCC..1
(-4600 6400);
FORCEPROP 3 LASTPIN (-4550 6350) SIG_NAME XP3R3V\g
J 0
(-4540 6360);
DISPLAY 0.659574 (-4540 6360);
PAINT MONO (-4540 6360);
DISPLAY INVISIBLE (-4540 6360);
FORCEPROP 1 LAST BODY_TYPE PLUMBING
J 0
(-4645 6357);
DISPLAY 0.340426 (-4645 6357);
PAINT GREEN (-4645 6357);
DISPLAY INVISIBLE (-4645 6357);
FORCEPROP 1 LAST PATH I72
J 0
(-4565 6490);
DISPLAY 0.808511 (-4565 6490);
PAINT GREEN (-4565 6490);
DISPLAY INVISIBLE (-4565 6490);
FORCEPROP 1 LAST CDS_LMAN_SYM_OUTLINE -250,250,250,-250
J 0
(-4600 6400);
DISPLAY 0.468085 (-4600 6400);
PAINT GREEN (-4600 6400);
DISPLAY INVISIBLE (-4600 6400);
FORCEPROP 2 LAST CDS_LIB cls
J 0
(-4600 6400);
DISPLAY INVISIBLE (-4600 6400);
FORCEPROP 1 LAST HDL_POWER XP3R3V
J 1
(-4545 6455);
DISPLAY 1.021277 (-4545 6455);
PAINT GREEN (-4545 6455);
FORCEPROP 0 LAST VOLTAGE 3.3
J 0
(-4800 6550);
DISPLAY 1.021277 (-4800 6550);
DISPLAY BOTH (-4800 6550);
FORCEADD VCC..1
(-9150 7100);
FORCEPROP 3 LASTPIN (-9100 7050) SIG_NAME XP3R3V_FPGA\g
J 0
(-9090 7060);
DISPLAY 0.659574 (-9090 7060);
PAINT MONO (-9090 7060);
DISPLAY INVISIBLE (-9090 7060);
FORCEPROP 2 LAST CDS_LIB cls
J 0
(-9150 7100);
DISPLAY INVISIBLE (-9150 7100);
FORCEPROP 1 LAST PATH I73
J 0
(-9115 7190);
DISPLAY 0.808511 (-9115 7190);
PAINT GREEN (-9115 7190);
DISPLAY INVISIBLE (-9115 7190);
FORCEPROP 1 LAST CDS_LMAN_SYM_OUTLINE -250,250,250,-250
J 0
(-9150 7100);
DISPLAY 0.468085 (-9150 7100);
PAINT GREEN (-9150 7100);
DISPLAY INVISIBLE (-9150 7100);
FORCEPROP 1 LAST BODY_TYPE PLUMBING
J 0
(-9195 7057);
DISPLAY 0.340426 (-9195 7057);
PAINT GREEN (-9195 7057);
DISPLAY INVISIBLE (-9195 7057);
FORCEPROP 1 LAST HDL_POWER XP3R3V_FPGA
J 1
(-9095 7155);
DISPLAY 1.021277 (-9095 7155);
PAINT GREEN (-9095 7155);
FORCEPROP 0 LAST VOLTAGE 3.3V
J 0
(-9400 7250);
DISPLAY 1.021277 (-9400 7250);
DISPLAY BOTH (-9400 7250);
FORCEADD SHEET_A1..1
(1150 1250);
FORCEPROP 2 LAST CUSTOM_TXT_CDS <XR_PAGE_TITLE>
J 0
(-14420 12600);
DISPLAY 0.638298 (-14420 12600);
PAINT PINK (-14420 12600);
FORCEPROP 1 LAST CUSTOM_TXT_CDS <DOCNO>
J 0
(-900 1635);
DISPLAY 0.978723 (-900 1635);
FORCEPROP 1 LAST CUSTOM_TXT_CDS <CON_PAGE_NUM>
J 0
(-1005 1300);
DISPLAY 0.978723 (-1005 1300);
FORCEPROP 1 LAST CUSTOM_TXT_CDS <DATE>
J 0
(450 1425);
DISPLAY 0.978723 (450 1425);
FORCEPROP 1 LAST CUSTOM_TXT_CDS <TITLE>
J 1
(-635 1880);
DISPLAY 0.978723 (-635 1880);
FORCEPROP 1 LAST CUSTOM_TXT_CDS <DESIGNER>
J 0
(450 1850);
DISPLAY 0.978723 (450 1850);
FORCEPROP 1 LAST CUSTOM_TXT_CDS <CON_TOTAL_PAGES>
J 0
(-695 1300);
DISPLAY 0.808511 (-695 1300);
FORCEPROP 1 LAST CUSTOM_TXT_CDS <ASSY_PN>
J 0
(-900 1425);
DISPLAY 0.978723 (-900 1425);
FORCEPROP 1 LAST CUSTOM_TXT_CDS <DOCREV>
J 0
(450 1625);
DISPLAY 0.978723 (450 1625);
FORCEPROP 1 LAST COMMENT_BODY TRUE
J 0
(1160 1305);
DISPLAY 0.808511 (1160 1305);
DISPLAY INVISIBLE (1160 1305);
FORCEPROP 2 LAST CDS_LIB cls
J 0
(1150 1250);
DISPLAY INVISIBLE (1150 1250);
FORCEPROP 1 LAST CDS_LMAN_SYM_OUTLINE -15850,11500,200,-200
J 0
(1150 1250);
DISPLAY 0.468085 (1150 1250);
PAINT GREEN (1150 1250);
DISPLAY INVISIBLE (1150 1250);
FORCEPROP 2 LAST PAGE_BORDER TRUE
J 0
(-14420 12600);
DISPLAY 0.638298 (-14420 12600);
PAINT PINK (-14420 12600);
DISPLAY INVISIBLE (-14420 12600);
FORCEPROP 1 LAST TITLE AIR_PRESSURE_SENSOR
J 0
(-1300 2150);
DISPLAY 2.425532 (-1300 2150);
PAINT GREEN (-1300 2150);
FORCEPROP 2 LAST CDS_XR_PAGE_TITLE CR-19 : @TIMECARD_LIB.TIMECARD(SCH_1):PAGE19
J 0
(-14420 12600);
DISPLAY 0.638298 (-14420 12600);
PAINT PINK (-14420 12600);
DISPLAY INVISIBLE (-14420 12600);
WIRE 16 -1 (-3800 5450)(-3800 5550);
WIRE 16 -1 (-4550 5450)(-4550 5550);
WIRE 16 -1 (-10000 6700)(-10000 6950);
WIRE 16 -1 (-9550 6950)(-10000 6950);
WIRE 16 -1 (-9100 6950)(-9550 6950);
WIRE 16 -1 (-9550 6700)(-9550 6950);
WIRE 16 -1 (-9100 6950)(-9100 7050);
WIRE 16 -1 (-9100 6950)(-9100 6750);
WIRE 16 -1 (-4550 5800)(-4550 6150);
WIRE 16 -1 (-3500 6150)(-4550 6150);
WIRE 16 -1 (-4550 6350)(-4550 6150);
WIRE 16 -1 (-3800 5800)(-3800 5950);
WIRE 16 -1 (-3800 6350)(-3800 5950);
WIRE 16 -1 (-3800 5950)(-3500 5950);
WIRE 16 -1 (-2450 5600)(-2450 5950);
WIRE 16 -1 (-2450 5950)(-2650 5950);
WIRE 16 -1 (-6750 8350)(-6900 8350);
WIRE 16 -1 (-6900 8350)(-6900 8250);
WIRE 16 -1 (-6900 8250)(-6750 8250);
WIRE 16 -1 (-6900 8050)(-6900 8250);
WIRE 16 -1 (-9100 9500)(-9100 9650);
WIRE 16 -1 (-9100 9650)(-9550 9650);
WIRE 16 -1 (-9550 9650)(-9550 9750);
WIRE 16 -1 (-9550 9500)(-9550 9650);
WIRE 16 -1 (-3950 8600)(-3950 8850);
WIRE 16 -1 (-3600 8850)(-3950 8850);
WIRE 16 -1 (-4350 8850)(-3950 8850);
WIRE 16 -1 (-4350 8600)(-4350 8850);
WIRE 16 -1 (-4700 8850)(-4350 8850);
WIRE 16 -1 (-4850 8850)(-4700 8850);
WIRE 16 -1 (-4700 8850)(-4700 8450);
WIRE 16 -1 (-4700 8450)(-4700 8350);
WIRE 16 -1 (-5200 8450)(-4700 8450);
WIRE 16 -1 (-4850 9050)(-4850 8850);
WIRE 16 -1 (-5800 8850)(-4850 8850);
WIRE 16 -1 (-4700 8350)(-5200 8350);
WIRE 16 -1 (-5200 8650)(-4850 8650);
WIRE 16 -1 (-4850 8650)(-4850 8550);
WIRE 16 -1 (-5200 8550)(-4850 8550);
WIRE 16 -1 (-4850 8550)(-4850 8250);
WIRE 16 -1 (-5200 8250)(-4850 8250);
WIRE 16 -1 (-4850 8250)(-4850 8050);
WIRE 16 -1 (-4850 8050)(-4350 8050);
WIRE 16 -1 (-4850 7950)(-4850 8050);
WIRE 16 -1 (-4350 8350)(-4350 8050);
WIRE 16 -1 (-4350 8050)(-3950 8050);
WIRE 16 -1 (-3950 8350)(-3950 8050);
WIRE 16 -1 (-2950 8050)(-3950 8050);
WIRE 16 -1 (-2950 8350)(-2950 8050);
WIRE 16 -1 (-2650 9050)(-2650 8850);
WIRE 16 -1 (-2650 8850)(-2950 8850);
WIRE 16 -1 (-2950 8600)(-2950 8850);
WIRE 16 -1 (-3200 8850)(-2950 8850);
WIRE 16 -1 (-11000 8750)(-9100 8750);
FORCEPROP 2 LAST SIG_NAME BF_ICP10100_I2C_SCL
J 0
(-10910 8760);
DISPLAY 1.021277 (-10910 8760);
WIRE 16 -1 (-9100 9250)(-9100 8750);
WIRE 16 -1 (-9100 8750)(-8700 8750);
WIRE 16 -1 (-11000 8850)(-9550 8850);
FORCEPROP 2 LAST SIG_NAME BF_ICP10100_I2C_SDA
J 0
(-10910 8860);
DISPLAY 1.021277 (-10910 8860);
WIRE 16 -1 (-9550 8850)(-8700 8850);
WIRE 16 -1 (-9550 9250)(-9550 8850);
WIRE 16 -1 (-11450 6050)(-9550 6050);
FORCEPROP 2 LAST SIG_NAME ICP10100_I2C_SCL
J 0
(-11360 6060);
DISPLAY 1.021277 (-11360 6060);
WIRE 16 -1 (-9550 6450)(-9550 6050);
WIRE 16 -1 (-8850 6050)(-9550 6050);
WIRE 16 -1 (-8850 6050)(-8700 6050);
WIRE 16 -1 (-8850 6050)(-8850 5550);
WIRE 16 -1 (-8850 5550)(-8450 5550);
WIRE 16 -1 (-7650 6150)(-7650 5450);
WIRE 16 -1 (-7900 6150)(-7650 6150);
WIRE 16 -1 (-7650 6150)(-6000 6150);
FORCEPROP 2 LAST SIG_NAME BF_ICP10100_I2C_SDA
J 0
(-7010 6160);
DISPLAY 1.021277 (-7010 6160);
WIRE 16 -1 (-7650 5450)(-8200 5450);
WIRE 16 -1 (-7700 6050)(-7700 5550);
WIRE 16 -1 (-7900 6050)(-7700 6050);
WIRE 16 -1 (-7700 6050)(-6000 6050);
FORCEPROP 2 LAST SIG_NAME BF_ICP10100_I2C_SCL
J 0
(-7010 6060);
DISPLAY 1.021277 (-7010 6060);
WIRE 16 -1 (-7700 5550)(-8200 5550);
WIRE 16 -1 (-9100 6500)(-9100 5850);
WIRE 16 -1 (-8700 5850)(-9100 5850);
WIRE 16 -1 (-11450 6150)(-10000 6150);
FORCEPROP 2 LAST SIG_NAME ICP10100_I2C_SDA
J 0
(-11360 6160);
DISPLAY 1.021277 (-11360 6160);
WIRE 16 -1 (-8900 6150)(-10000 6150);
WIRE 16 -1 (-10000 6450)(-10000 6150);
WIRE 16 -1 (-8900 6150)(-8900 5450);
WIRE 16 -1 (-8900 6150)(-8700 6150);
WIRE 16 -1 (-8900 5450)(-8450 5450);
WIRE 16 -1 (-5800 8350)(-5450 8350);
WIRE 16 -1 (-8450 8850)(-6750 8850);
FORCEPROP 2 LAST SIG_NAME R_ICP10100_I2C_SDA
J 0
(-7810 8860);
DISPLAY 1.021277 (-7810 8860);
WIRE 16 -1 (-5800 8250)(-5450 8250);
WIRE 16 -1 (-5800 8550)(-5450 8550);
WIRE 16 -1 (-5800 8650)(-5450 8650);
WIRE 16 -1 (-5800 8450)(-5450 8450);
WIRE 16 -1 (-8450 8750)(-6750 8750);
FORCEPROP 2 LAST SIG_NAME R_ICP10100_I2C_SCL
J 0
(-7810 8760);
DISPLAY 1.021277 (-7810 8760);
DOT 1 (-8850 6050);
DOT 1 (-10000 6150);
DOT 1 (-9550 6050);
DOT 1 (-9550 6950);
DOT 1 (-9100 6950);
DOT 1 (-7650 6150);
DOT 1 (-7700 6050);
DOT 1 (-4550 6150);
DOT 1 (-2950 8850);
DOT 1 (-3950 8850);
DOT 1 (-4350 8850);
DOT 1 (-4850 8850);
DOT 1 (-4700 8850);
DOT 1 (-4850 8550);
DOT 1 (-4700 8450);
DOT 1 (-4850 8250);
DOT 1 (-6900 8250);
DOT 1 (-3950 8050);
DOT 1 (-4350 8050);
DOT 1 (-4850 8050);
DOT 1 (-9100 8750);
DOT 1 (-9550 9650);
DOT 1 (-9550 8850);
DOT 1 (-3800 5950);
DOT 1 (-8900 6150);
FORCENOTE
PCA9617ADPJ
(-8400 6400) 0;
DISPLAY LEFT (-8400 6400);
DISPLAY 1.021277 (-8400 6400);
FORCENOTE
U32: - G220-10219-01 (EVT) SHOW NOT FOR NEW DESIGN IN THE ENOVIA SYSTEM.
(-5250 5050) 0;
DISPLAY LEFT (-5250 5050);
DISPLAY 1.021277 (-5250 5050);
FORCENOTE
AIR_PRESSURE_SENSOR
(-8800 11450) 0;
DISPLAY LEFT (-8800 11450);
DISPLAY 4.914894 (-8800 11450);
FORCENOTE
I2C ADDR = 0X63. 
(-8400 8400) 0;
DISPLAY LEFT (-8400 8400);
DISPLAY 1.595745 (-8400 8400);
FORCENOTE
- PI6ULS5V9617AUEX: VCC(B) AND VCC(A) CAN BE APPLIED IN ANY SEQUENCE AT POWER-UP
(-4200 4750) 0;
DISPLAY LEFT (-4200 4750);
DISPLAY 1.021277 (-4200 4750);
FORCENOTE
- THE EVT >> DVT PHASE, CHANGE G220-10219-01 TO G223-10278-01.
(-5000 4950) 0;
DISPLAY LEFT (-5000 4950);
DISPLAY 1.021277 (-5000 4950);
FORCENOTE
- G223-10278-01:
(-5000 4750) 0;
DISPLAY LEFT (-5000 4750);
DISPLAY 1.021277 (-5000 4750);
FORCENOTE
- PCA9617ADPJ     : VCC(B) AND VCC(A) CAN BE APPLIED IN ANY SEQUENCE AT POWER-UP
(-4200 4650) 0;
DISPLAY LEFT (-4200 4650);
DISPLAY 1.021277 (-4200 4650);
FORCENOTE
- THUS, TO SUPPORT TI CHIP (TCA9617ADGKR). FOR THE DVT, CONNECT VCC_B PIN TO XP3R3V.
(-5000 4400) 0;
DISPLAY LEFT (-5000 4400);
DISPLAY 1.021277 (-5000 4400);
FORCENOTE
- TCA9617ADGKR    : DURING POWER-UP, VCCB MUST RISE BEFORE VCCA. 
(-4200 4550) 0;
DISPLAY LEFT (-4200 4550);
DISPLAY 1.021277 (-4200 4550);
QUIT
